FILE_TYPE = MACRO_DRAWING;
SET COLOR_WIRE YELLOW;
SET COLOR_PROP MONO;
SET COLOR_DOT WHITE;
SET COLOR_ARC YELLOW;
SET COLOR_BODY GREEN;
SET COLOR_NOTE MONO;
SET PROP_DISPLAY VALUE;
SET PAGE_NUMBER P219;
FORCEADD PVDDQ_DEF..1
(4075 1875);
FORCEPROP 3 LASTPIN (4075 1825) SIG_NAME PVDDQ_DEF\g
J 0
(4085 1835);
DISPLAY 0.659574 (4085 1835);
PAINT MONO (4085 1835);
DISPLAY INVISIBLE (4085 1835);
FORCEPROP 1 LAST HDL_POWER PVDDQ_DEF
J 1
(4075 1925);
DISPLAY 0.872340 (4075 1925);
PAINT GREEN (4075 1925);
DISPLAY INVISIBLE (4075 1925);
FORCEPROP 1 LAST BODY_TYPE PLUMBING
J 0
(4030 1832);
DISPLAY 0.340426 (4030 1832);
PAINT GREEN (4030 1832);
DISPLAY INVISIBLE (4030 1832);
FORCEPROP 2 LAST CDS_LIB mstr_symbols
J 0
(4075 1875);
PAINT ORANGE (4075 1875);
DISPLAY INVISIBLE (4075 1875);
FORCEPROP 1 LAST VOLTAGE 1.2V
J 0
(4030 1832);
DISPLAY 0.340426 (4030 1832);
PAINT SKYBLUE (4030 1832);
DISPLAY INVISIBLE (4030 1832);
FORCEPROP 1 LAST PATH I1
J 0
(4125 1900);
DISPLAY 0.872340 (4125 1900);
PAINT AQUA (4125 1900);
DISPLAY INVISIBLE (4125 1900);
FORCEADD IR354XX..1
(1550 2075);
FORCEPROP 2 LASTPIN (1050 1775) $PN 33
J 2
(1040 1785);
DISPLAY 0.617021 (1040 1785);
PAINT ORANGE (1040 1785);
FORCEPROP 2 LASTPIN (1050 1725) $PN 32
J 2
(1040 1735);
DISPLAY 0.617021 (1040 1735);
PAINT ORANGE (1040 1735);
FORCEPROP 2 LASTPIN (1050 1975) $PN 34
J 2
(1040 1985);
DISPLAY 0.617021 (1040 1985);
PAINT ORANGE (1040 1985);
FORCEPROP 2 LASTPIN (1050 1875) $PN 39
J 2
(1040 1885);
DISPLAY 0.617021 (1040 1885);
PAINT ORANGE (1040 1885);
FORCEPROP 2 LASTPIN (1050 2325) $PN 35
J 2
(1040 2335);
DISPLAY 0.617021 (1040 2335);
PAINT ORANGE (1040 2335);
FORCEPROP 2 LASTPIN (1050 2075) $PN 6
J 2
(1040 2085);
DISPLAY 0.617021 (1040 2085);
PAINT ORANGE (1040 2085);
FORCEPROP 2 LASTPIN (1050 2125) $PN 41
J 2
(1040 2135);
DISPLAY 0.617021 (1040 2135);
PAINT ORANGE (1040 2135);
FORCEPROP 2 LASTPIN (1050 2625) $PN 3
J 2
(1040 2635);
DISPLAY 0.617021 (1040 2635);
PAINT ORANGE (1040 2635);
FORCEPROP 2 LASTPIN (1050 2425) $PN 4
J 2
(1040 2435);
DISPLAY 0.617021 (1040 2435);
PAINT ORANGE (1040 2435);
FORCEPROP 2 LASTPIN (1050 2525) $PN 25
J 2
(1040 2535);
DISPLAY 0.617021 (1040 2535);
PAINT ORANGE (1040 2535);
FORCEPROP 2 LASTPIN (1050 2575) $PN 30
J 2
(1040 2585);
DISPLAY 0.617021 (1040 2585);
PAINT ORANGE (1040 2585);
FORCEPROP 2 LASTPIN (1050 2225) $PN 1
J 2
(1040 2235);
DISPLAY 0.617021 (1040 2235);
PAINT ORANGE (1040 2235);
FORCEPROP 2 LAST NO_XNET_CONNECTION 1
J 0
(1100 2925);
PAINT MONO (1100 2925);
FORCEPROP 1 LAST MATERIAL IC
J 0
(1100 2825);
DISPLAY 0.617021 (1100 2825);
PAINT SKYBLUE (1100 2825);
FORCEPROP 1 LAST LOCATION EU7A1
J 0
(1100 2875);
DISPLAY 0.617021 (1100 2875);
PAINT AQUA (1100 2875);
FORCEPROP 1 LAST VALUE IR35411
J 1
(1550 2700);
DISPLAY 0.617021 (1550 2700);
PAINT SKYBLUE (1550 2700);
FORCEPROP 2 LASTPIN (2050 1525) $PN 5
J 0
(2060 1535);
DISPLAY 0.617021 (2060 1535);
PAINT ORANGE (2060 1535);
FORCEPROP 2 LASTPIN (2050 1775) $PN 10
J 0
(2060 1785);
DISPLAY 0.617021 (2060 1785);
PAINT ORANGE (2060 1785);
FORCEPROP 2 LASTPIN (2050 1625) $PN 40
J 0
(2060 1635);
DISPLAY 0.617021 (2060 1635);
PAINT ORANGE (2060 1635);
FORCEPROP 2 LASTPIN (2050 1575) $PN 7
J 0
(2060 1585);
DISPLAY 0.617021 (2060 1585);
PAINT ORANGE (2060 1585);
FORCEPROP 2 LASTPIN (2050 1675) $PN 2
J 0
(2060 1685);
DISPLAY 0.617021 (2060 1685);
PAINT ORANGE (2060 1685);
FORCEPROP 2 LASTPIN (2050 2375) $PN 31
J 0
(2060 2385);
DISPLAY 0.617021 (2060 2385);
PAINT ORANGE (2060 2385);
FORCEPROP 2 LASTPIN (2050 2425) $PN 37
J 0
(2060 2435);
DISPLAY 0.617021 (2060 2435);
PAINT ORANGE (2060 2435);
FORCEPROP 2 LASTPIN (2050 2125) $PN 36
J 0
(2060 2135);
DISPLAY 0.617021 (2060 2135);
PAINT ORANGE (2060 2135);
FORCEPROP 2 LASTPIN (2050 2625) $PN 38
J 0
(2060 2635);
DISPLAY 0.617021 (2060 2635);
PAINT ORANGE (2060 2635);
FORCEPROP 1 LAST PART_NUMBER H73688-001
J 0
(1150 1375);
DISPLAY 0.617021 (1150 1375);
PAINT BLUE (1150 1375);
FORCEPROP 2 LAST CDS_LOCATION EU7A1
J 0
(1100 2875);
PAINT GREEN (1100 2875);
DISPLAY INVISIBLE (1100 2875);
FORCEPROP 2 LAST SEC 1
J 0
(1100 2925);
DISPLAY 0.680851 (1100 2925);
PAINT MONO (1100 2925);
DISPLAY INVISIBLE (1100 2925);
FORCEPROP 2 LAST SEC_TYPE SM
J 0
(1100 2925);
DISPLAY 1.021277 (1100 2925);
PAINT ORANGE (1100 2925);
DISPLAY INVISIBLE (1100 2925);
FORCEPROP 1 LAST PACK_TYPE SM
J 0
(1100 2925);
PAINT SKYBLUE (1100 2925);
DISPLAY INVISIBLE (1100 2925);
FORCEPROP 1 LAST PATH I106
J 0
(1550 2825);
PAINT GREEN (1550 2825);
DISPLAY INVISIBLE (1550 2825);
FORCEPROP 2 LAST CDS_LIB mstr_discrete
J 0
(1550 2075);
PAINT ORANGE (1550 2075);
DISPLAY INVISIBLE (1550 2075);
FORCEADD IR354XX..1
(1575 -50);
FORCEPROP 1 LAST PART_NUMBER H73688-001
J 0
(1200 -750);
DISPLAY 0.617021 (1200 -750);
PAINT BLUE (1200 -750);
FORCEPROP 2 LASTPIN (2075 500) $PN 38
J 0
(2085 510);
DISPLAY 0.617021 (2085 510);
PAINT ORANGE (2085 510);
FORCEPROP 2 LASTPIN (2075 0) $PN 36
J 0
(2085 10);
DISPLAY 0.617021 (2085 10);
PAINT ORANGE (2085 10);
FORCEPROP 2 LASTPIN (1075 -350) $PN 33
J 2
(1065 -340);
DISPLAY 0.617021 (1065 -340);
PAINT ORANGE (1065 -340);
FORCEPROP 2 LASTPIN (1075 -400) $PN 32
J 2
(1065 -390);
DISPLAY 0.617021 (1065 -390);
PAINT ORANGE (1065 -390);
FORCEPROP 2 LASTPIN (1075 -150) $PN 34
J 2
(1065 -140);
DISPLAY 0.617021 (1065 -140);
PAINT ORANGE (1065 -140);
FORCEPROP 2 LASTPIN (1075 -250) $PN 39
J 2
(1065 -240);
DISPLAY 0.617021 (1065 -240);
PAINT ORANGE (1065 -240);
FORCEPROP 2 LASTPIN (1075 -50) $PN 6
J 2
(1065 -40);
DISPLAY 0.617021 (1065 -40);
PAINT ORANGE (1065 -40);
FORCEPROP 2 LASTPIN (2075 -600) $PN 5
J 0
(2085 -590);
DISPLAY 0.617021 (2085 -590);
PAINT ORANGE (2085 -590);
FORCEPROP 2 LASTPIN (2075 -550) $PN 7
J 0
(2085 -540);
DISPLAY 0.617021 (2085 -540);
PAINT ORANGE (2085 -540);
FORCEPROP 2 LASTPIN (2075 -350) $PN 10
J 0
(2085 -340);
DISPLAY 0.617021 (2085 -340);
PAINT ORANGE (2085 -340);
FORCEPROP 2 LASTPIN (2075 -500) $PN 40
J 0
(2085 -490);
DISPLAY 0.617021 (2085 -490);
PAINT ORANGE (2085 -490);
FORCEPROP 2 LASTPIN (2075 -450) $PN 2
J 0
(2085 -440);
DISPLAY 0.617021 (2085 -440);
PAINT ORANGE (2085 -440);
FORCEPROP 2 LASTPIN (1075 200) $PN 35
J 2
(1065 210);
DISPLAY 0.617021 (1065 210);
PAINT ORANGE (1065 210);
FORCEPROP 2 LASTPIN (1075 0) $PN 41
J 2
(1065 10);
DISPLAY 0.617021 (1065 10);
PAINT ORANGE (1065 10);
FORCEPROP 2 LASTPIN (1075 400) $PN 25
J 2
(1065 410);
DISPLAY 0.617021 (1065 410);
PAINT ORANGE (1065 410);
FORCEPROP 2 LASTPIN (1075 450) $PN 30
J 2
(1065 460);
DISPLAY 0.617021 (1065 460);
PAINT ORANGE (1065 460);
FORCEPROP 2 LASTPIN (1075 100) $PN 1
J 2
(1065 110);
DISPLAY 0.617021 (1065 110);
PAINT ORANGE (1065 110);
FORCEPROP 2 LASTPIN (1075 300) $PN 4
J 2
(1065 310);
DISPLAY 0.617021 (1065 310);
PAINT ORANGE (1065 310);
FORCEPROP 2 LASTPIN (1075 500) $PN 3
J 2
(1065 510);
DISPLAY 0.617021 (1065 510);
PAINT ORANGE (1065 510);
FORCEPROP 2 LAST NO_XNET_CONNECTION 1
J 0
(1125 800);
PAINT MONO (1125 800);
FORCEPROP 1 LAST LOCATION EU7A4
J 0
(1125 750);
DISPLAY 0.617021 (1125 750);
PAINT AQUA (1125 750);
FORCEPROP 1 LAST VALUE IR35411
J 1
(1575 575);
DISPLAY 0.617021 (1575 575);
PAINT SKYBLUE (1575 575);
FORCEPROP 2 LASTPIN (2075 300) $PN 37
J 0
(2085 310);
DISPLAY 0.617021 (2085 310);
PAINT ORANGE (2085 310);
FORCEPROP 1 LAST MATERIAL IC
J 0
(1125 700);
DISPLAY 0.617021 (1125 700);
PAINT SKYBLUE (1125 700);
FORCEPROP 2 LASTPIN (2075 250) $PN 31
J 0
(2085 260);
DISPLAY 0.617021 (2085 260);
PAINT ORANGE (2085 260);
FORCEPROP 2 LAST CDS_LIB mstr_discrete
J 0
(1575 -50);
PAINT ORANGE (1575 -50);
DISPLAY INVISIBLE (1575 -50);
FORCEPROP 2 LAST CDS_LOCATION EU7A4
J 0
(1125 750);
PAINT GREEN (1125 750);
DISPLAY INVISIBLE (1125 750);
FORCEPROP 2 LAST SEC 1
J 0
(1125 800);
DISPLAY 0.680851 (1125 800);
PAINT MONO (1125 800);
DISPLAY INVISIBLE (1125 800);
FORCEPROP 2 LAST SEC_TYPE SM
J 0
(1125 800);
DISPLAY 1.021277 (1125 800);
PAINT ORANGE (1125 800);
DISPLAY INVISIBLE (1125 800);
FORCEPROP 1 LAST PACK_TYPE SM
J 0
(1125 800);
PAINT SKYBLUE (1125 800);
DISPLAY INVISIBLE (1125 800);
FORCEPROP 1 LAST PATH I107
J 0
(1575 700);
PAINT GREEN (1575 700);
DISPLAY INVISIBLE (1575 700);
FORCEADD RES..2
(4375 2250);
FORCEPROP 1 LAST TOLERANCE 1%
J 0
(4420 2275);
DISPLAY 0.617021 (4420 2275);
PAINT SKYBLUE (4420 2275);
FORCEPROP 1 LAST WATTAGE 1/16W
J 0
(4415 2225);
DISPLAY 0.617021 (4415 2225);
PAINT SKYBLUE (4415 2225);
FORCEPROP 1 LAST PACK_TYPE 0402
J 0
(4415 2075);
DISPLAY 0.617021 (4415 2075);
PAINT SKYBLUE (4415 2075);
FORCEPROP 1 LAST MATERIAL EMPTY
J 0
(4415 2175);
DISPLAY 0.617021 (4415 2175);
PAINT RED (4415 2175);
FORCEPROP 1 LAST LOCATION R7A20
J 0
(4420 2375);
DISPLAY 0.617021 (4420 2375);
PAINT AQUA (4420 2375);
FORCEPROP 1 LAST VALUE 68.1K
J 0
(4420 2325);
DISPLAY 0.617021 (4420 2325);
PAINT SKYBLUE (4420 2325);
FORCEPROP 1 LAST PART_NUMBER G21796-187
J 0
(4415 2125);
DISPLAY 0.617021 (4415 2125);
PAINT BLUE (4415 2125);
FORCEPROP 1 LASTPIN (4375 2150) $PN 2
J 0
(4380 2160);
DISPLAY 0.787234 (4380 2160);
PAINT ORANGE (4380 2160);
DISPLAY INVISIBLE (4380 2160);
FORCEPROP 2 LAST CDS_LIB mstr_discrete
J 0
(4375 2250);
PAINT ORANGE (4375 2250);
DISPLAY INVISIBLE (4375 2250);
FORCEPROP 1 LASTPIN (4375 2350) $PN 1
J 0
(4380 2312);
DISPLAY 0.787234 (4380 2312);
PAINT ORANGE (4380 2312);
DISPLAY INVISIBLE (4380 2312);
FORCEPROP 1 LAST PATH I108
J 0
(4425 2425);
DISPLAY 0.978723 (4425 2425);
PAINT WHITE (4425 2425);
DISPLAY INVISIBLE (4425 2425);
FORCEPROP 2 LAST $SEC 1
J 0
(4425 2475);
PAINT MONO (4425 2475);
DISPLAY INVISIBLE (4425 2475);
FORCEPROP 2 LAST CDS_SEC 1
J 0
(4425 2475);
PAINT MONO (4425 2475);
DISPLAY INVISIBLE (4425 2475);
FORCEADD GND..1
(4375 1950);
FORCEPROP 3 LASTPIN (4375 2000) SIG_NAME GND\g
J 0
(4385 2010);
DISPLAY 0.659574 (4385 2010);
PAINT MONO (4385 2010);
DISPLAY INVISIBLE (4385 2010);
FORCEPROP 2 LAST ROOM PVCCIN_CPU0_PWR_VR
J 0
(3825 2025);
DISPLAY 1.936170 (3825 2025);
PAINT ORANGE (3825 2025);
DISPLAY INVISIBLE (3825 2025);
FORCEPROP 2 LAST BOM_COST PROC_VRD_VCCIN_CPU0
J 0
(4000 2025);
DISPLAY 1.446809 (4000 2025);
PAINT MONO (4000 2025);
DISPLAY INVISIBLE (4000 2025);
FORCEPROP 1 LAST BODY_TYPE PLUMBING
J 0
(4330 1907);
DISPLAY 0.340426 (4330 1907);
PAINT GREEN (4330 1907);
DISPLAY INVISIBLE (4330 1907);
FORCEPROP 1 LAST PATH I109
J 0
(4450 1950);
DISPLAY 0.872340 (4450 1950);
PAINT AQUA (4450 1950);
DISPLAY INVISIBLE (4450 1950);
FORCEPROP 2 LAST CDS_LIB mstr_symbols
J 0
(4375 1950);
PAINT ORANGE (4375 1950);
DISPLAY INVISIBLE (4375 1950);
FORCEPROP 1 LAST SIZE 1B
J 0
(4450 1900);
DISPLAY 1.723404 (4450 1900);
PAINT GREEN (4450 1900);
DISPLAY INVISIBLE (4450 1900);
FORCEPROP 1 LAST VOLTAGE 0
J 0
(4375 1950);
PAINT SKYBLUE (4375 1950);
DISPLAY INVISIBLE (4375 1950);
FORCEPROP 1 LAST HDL_POWER GND
J 0
(4375 2100);
DISPLAY 1.723404 (4375 2100);
PAINT GREEN (4375 2100);
DISPLAY INVISIBLE (4375 2100);
FORCEADD RES..2
(4375 100);
FORCEPROP 1 LAST PACK_TYPE 0402
J 0
(4415 -75);
DISPLAY 0.617021 (4415 -75);
PAINT SKYBLUE (4415 -75);
FORCEPROP 1 LAST PART_NUMBER G21796-187
J 0
(4415 -25);
DISPLAY 0.617021 (4415 -25);
PAINT BLUE (4415 -25);
FORCEPROP 1 LAST TOLERANCE 1%
J 0
(4420 125);
DISPLAY 0.617021 (4420 125);
PAINT SKYBLUE (4420 125);
FORCEPROP 1 LAST WATTAGE 1/16W
J 0
(4415 75);
DISPLAY 0.617021 (4415 75);
PAINT SKYBLUE (4415 75);
FORCEPROP 1 LAST VALUE 68.1K
J 0
(4420 175);
DISPLAY 0.617021 (4420 175);
PAINT SKYBLUE (4420 175);
FORCEPROP 1 LAST LOCATION R7A21
J 0
(4420 225);
DISPLAY 0.617021 (4420 225);
PAINT AQUA (4420 225);
FORCEPROP 1 LAST MATERIAL EMPTY
J 0
(4415 25);
DISPLAY 0.617021 (4415 25);
PAINT RED (4415 25);
FORCEPROP 1 LASTPIN (4375 0) $PN 2
J 0
(4380 10);
DISPLAY 0.787234 (4380 10);
PAINT ORANGE (4380 10);
DISPLAY INVISIBLE (4380 10);
FORCEPROP 2 LAST CDS_LIB mstr_discrete
J 0
(4375 100);
PAINT ORANGE (4375 100);
DISPLAY INVISIBLE (4375 100);
FORCEPROP 1 LASTPIN (4375 200) $PN 1
J 0
(4380 162);
DISPLAY 0.787234 (4380 162);
PAINT ORANGE (4380 162);
DISPLAY INVISIBLE (4380 162);
FORCEPROP 1 LAST PATH I110
J 0
(4425 275);
DISPLAY 0.978723 (4425 275);
PAINT WHITE (4425 275);
DISPLAY INVISIBLE (4425 275);
FORCEPROP 2 LAST $SEC 1
J 0
(4425 325);
PAINT MONO (4425 325);
DISPLAY INVISIBLE (4425 325);
FORCEPROP 2 LAST CDS_SEC 1
J 0
(4425 325);
PAINT MONO (4425 325);
DISPLAY INVISIBLE (4425 325);
FORCEADD GND..1
(4375 -200);
FORCEPROP 3 LASTPIN (4375 -150) SIG_NAME GND\g
J 0
(4385 -140);
DISPLAY 0.659574 (4385 -140);
PAINT MONO (4385 -140);
DISPLAY INVISIBLE (4385 -140);
FORCEPROP 2 LAST ROOM PVCCIN_CPU0_PWR_VR
J 0
(3825 -125);
DISPLAY 1.936170 (3825 -125);
PAINT ORANGE (3825 -125);
DISPLAY INVISIBLE (3825 -125);
FORCEPROP 2 LAST BOM_COST PROC_VRD_VCCIN_CPU0
J 0
(4000 -125);
DISPLAY 1.446809 (4000 -125);
PAINT MONO (4000 -125);
DISPLAY INVISIBLE (4000 -125);
FORCEPROP 1 LAST BODY_TYPE PLUMBING
J 0
(4330 -243);
DISPLAY 0.340426 (4330 -243);
PAINT GREEN (4330 -243);
DISPLAY INVISIBLE (4330 -243);
FORCEPROP 1 LAST PATH I111
J 0
(4450 -200);
DISPLAY 0.872340 (4450 -200);
PAINT AQUA (4450 -200);
DISPLAY INVISIBLE (4450 -200);
FORCEPROP 2 LAST CDS_LIB mstr_symbols
J 0
(4375 -200);
PAINT ORANGE (4375 -200);
DISPLAY INVISIBLE (4375 -200);
FORCEPROP 1 LAST SIZE 1B
J 0
(4450 -250);
DISPLAY 1.723404 (4450 -250);
PAINT GREEN (4450 -250);
DISPLAY INVISIBLE (4450 -250);
FORCEPROP 1 LAST VOLTAGE 0
J 0
(4375 -200);
PAINT SKYBLUE (4375 -200);
DISPLAY INVISIBLE (4375 -200);
FORCEPROP 1 LAST HDL_POWER GND
J 0
(4375 -50);
DISPLAY 1.723404 (4375 -50);
PAINT GREEN (4375 -50);
DISPLAY INVISIBLE (4375 -50);
FORCEADD P5V_STBY..1
(25 3100);
FORCEPROP 3 LASTPIN (25 3050) SIG_NAME P5V_STBY\g
J 0
(35 3060);
DISPLAY 0.659574 (35 3060);
PAINT MONO (35 3060);
DISPLAY INVISIBLE (35 3060);
FORCEPROP 1 LAST HDL_POWER P5V_STBY
J 0
(-275 2975);
DISPLAY 0.872340 (-275 2975);
PAINT ORANGE (-275 2975);
DISPLAY INVISIBLE (-275 2975);
FORCEPROP 1 LAST BODY_TYPE PLUMBING
J 0
(-20 3057);
DISPLAY 0.340426 (-20 3057);
PAINT GREEN (-20 3057);
DISPLAY INVISIBLE (-20 3057);
FORCEPROP 1 LAST VOLTAGE 5.0V
J 0
(-20 3057);
DISPLAY 0.340426 (-20 3057);
PAINT SKYBLUE (-20 3057);
DISPLAY INVISIBLE (-20 3057);
FORCEPROP 2 LAST CDS_LIB mstr_symbols
J 0
(25 3100);
PAINT ORANGE (25 3100);
DISPLAY INVISIBLE (25 3100);
FORCEPROP 1 LAST SIZE 1B
J 0
(70 3122);
DISPLAY 0.340426 (70 3122);
PAINT GREEN (70 3122);
DISPLAY INVISIBLE (70 3122);
FORCEPROP 1 LAST PATH I112
J 0
(70 3102);
DISPLAY 0.340426 (70 3102);
PAINT GREEN (70 3102);
DISPLAY INVISIBLE (70 3102);
FORCEADD CAP_A..1
(875 -550);
FORCEPROP 0 LAST STATUS NOPOP
J 0
(625 -650);
DISPLAY 1.021277 (625 -650);
PAINT ORANGE (625 -650);
FORCEPROP 1 LAST LOCATION CT46
J 0
(725 -550);
DISPLAY 0.617021 (725 -550);
PAINT AQUA (725 -550);
FORCEPROP 1 LAST MATERIAL X7R
J 0
(925 -650);
DISPLAY 0.617021 (925 -650);
PAINT SKYBLUE (925 -650);
FORCEPROP 1 LAST PACK_TYPE 0402V
J 0
(925 -750);
DISPLAY 0.617021 (925 -750);
PAINT SKYBLUE (925 -750);
FORCEPROP 1 LAST PART_NUMBER A36096-030
J 0
(925 -700);
DISPLAY 0.617021 (925 -700);
PAINT BLUE (925 -700);
FORCEPROP 1 LAST VOLTAGE 16V
J 0
(925 -550);
DISPLAY 0.617021 (925 -550);
PAINT SKYBLUE (925 -550);
FORCEPROP 1 LAST TOLERANCE 10%
J 0
(925 -600);
DISPLAY 0.617021 (925 -600);
PAINT SKYBLUE (925 -600);
FORCEPROP 1 LAST VALUE 0.1UF
J 0
(925 -500);
DISPLAY 0.617021 (925 -500);
PAINT SKYBLUE (925 -500);
FORCEPROP 1 LASTPIN (875 -650) $PN 2
J 0
(885 -670);
DISPLAY 0.787234 (885 -670);
PAINT ORANGE (885 -670);
DISPLAY INVISIBLE (885 -670);
FORCEPROP 1 LASTPIN (875 -450) $PN 1
J 0
(885 -470);
DISPLAY 0.787234 (885 -470);
PAINT ORANGE (885 -470);
DISPLAY INVISIBLE (885 -470);
FORCEPROP 2 LAST ROOM PVCCIN_CPU0_PWR_VR
J 0
(925 -400);
DISPLAY 1.361702 (925 -400);
PAINT ORANGE (925 -400);
DISPLAY INVISIBLE (925 -400);
FORCEPROP 1 LAST PATH I113
J 0
(925 -400);
DISPLAY 0.978723 (925 -400);
PAINT WHITE (925 -400);
DISPLAY INVISIBLE (925 -400);
FORCEPROP 2 LAST CDS_LIB dev_discrete
J 0
(875 -550);
PAINT MONO (875 -550);
DISPLAY INVISIBLE (875 -550);
FORCEADD GND..1
(875 -825);
FORCEPROP 3 LASTPIN (875 -775) SIG_NAME GND\g
J 0
(885 -765);
DISPLAY 0.659574 (885 -765);
PAINT MONO (885 -765);
DISPLAY INVISIBLE (885 -765);
FORCEPROP 1 LAST HDL_POWER GND
J 0
(875 -675);
DISPLAY 1.723404 (875 -675);
PAINT GREEN (875 -675);
DISPLAY INVISIBLE (875 -675);
FORCEPROP 1 LAST VOLTAGE 0
J 0
(875 -825);
PAINT SKYBLUE (875 -825);
DISPLAY INVISIBLE (875 -825);
FORCEPROP 1 LAST SIZE 1B
J 0
(950 -875);
DISPLAY 1.723404 (950 -875);
PAINT GREEN (950 -875);
DISPLAY INVISIBLE (950 -875);
FORCEPROP 2 LAST BOM_COST PROC_VRD_VCCIN_CPU0
J 0
(500 -750);
DISPLAY 1.446809 (500 -750);
PAINT MONO (500 -750);
DISPLAY INVISIBLE (500 -750);
FORCEPROP 2 LAST ROOM PVCCIN_CPU0_PWR_VR
J 0
(325 -750);
DISPLAY 1.936170 (325 -750);
PAINT ORANGE (325 -750);
DISPLAY INVISIBLE (325 -750);
FORCEPROP 1 LAST BODY_TYPE PLUMBING
J 0
(830 -868);
DISPLAY 0.340426 (830 -868);
PAINT GREEN (830 -868);
DISPLAY INVISIBLE (830 -868);
FORCEPROP 1 LAST PATH I114
J 0
(950 -825);
DISPLAY 0.872340 (950 -825);
PAINT AQUA (950 -825);
DISPLAY INVISIBLE (950 -825);
FORCEPROP 2 LAST CDS_LIB mstr_symbols
J 0
(875 -825);
PAINT MONO (875 -825);
DISPLAY INVISIBLE (875 -825);
FORCEADD CAP_A..1
(825 1575);
FORCEPROP 1 LAST VALUE 0.1UF
J 0
(875 1625);
DISPLAY 0.617021 (875 1625);
PAINT SKYBLUE (875 1625);
FORCEPROP 1 LAST MATERIAL X7R
J 0
(875 1475);
DISPLAY 0.617021 (875 1475);
PAINT SKYBLUE (875 1475);
FORCEPROP 1 LAST VOLTAGE 16V
J 0
(875 1575);
DISPLAY 0.617021 (875 1575);
PAINT SKYBLUE (875 1575);
FORCEPROP 1 LAST TOLERANCE 10%
J 0
(875 1525);
DISPLAY 0.617021 (875 1525);
PAINT SKYBLUE (875 1525);
FORCEPROP 1 LAST LOCATION CT45
J 0
(675 1575);
DISPLAY 0.617021 (675 1575);
PAINT AQUA (675 1575);
FORCEPROP 1 LAST PART_NUMBER A36096-030
J 0
(875 1425);
DISPLAY 0.617021 (875 1425);
PAINT BLUE (875 1425);
FORCEPROP 1 LAST PACK_TYPE 0402V
J 0
(875 1375);
DISPLAY 0.617021 (875 1375);
PAINT SKYBLUE (875 1375);
FORCEPROP 0 LAST STATUS NOPOP
J 0
(550 1475);
DISPLAY 1.021277 (550 1475);
PAINT ORANGE (550 1475);
FORCEPROP 2 LAST ROOM PVCCIN_CPU0_PWR_VR
J 0
(875 1725);
DISPLAY 1.361702 (875 1725);
PAINT ORANGE (875 1725);
DISPLAY INVISIBLE (875 1725);
FORCEPROP 1 LAST PATH I116
J 0
(875 1725);
DISPLAY 0.978723 (875 1725);
PAINT WHITE (875 1725);
DISPLAY INVISIBLE (875 1725);
FORCEPROP 2 LAST CDS_LIB dev_discrete
J 0
(825 1575);
PAINT MONO (825 1575);
DISPLAY INVISIBLE (825 1575);
FORCEPROP 1 LASTPIN (825 1675) $PN 1
J 0
(835 1655);
DISPLAY 0.787234 (835 1655);
PAINT ORANGE (835 1655);
DISPLAY INVISIBLE (835 1655);
FORCEPROP 1 LASTPIN (825 1475) $PN 2
J 0
(835 1455);
DISPLAY 0.787234 (835 1455);
PAINT ORANGE (835 1455);
DISPLAY INVISIBLE (835 1455);
FORCEADD GND..1
(825 1325);
FORCEPROP 3 LASTPIN (825 1375) SIG_NAME GND\g
J 0
(835 1385);
DISPLAY 0.659574 (835 1385);
PAINT MONO (835 1385);
DISPLAY INVISIBLE (835 1385);
FORCEPROP 2 LAST CDS_LIB mstr_symbols
J 0
(825 1325);
PAINT MONO (825 1325);
DISPLAY INVISIBLE (825 1325);
FORCEPROP 1 LAST PATH I117
J 0
(900 1325);
DISPLAY 0.872340 (900 1325);
PAINT AQUA (900 1325);
DISPLAY INVISIBLE (900 1325);
FORCEPROP 1 LAST BODY_TYPE PLUMBING
J 0
(780 1282);
DISPLAY 0.340426 (780 1282);
PAINT GREEN (780 1282);
DISPLAY INVISIBLE (780 1282);
FORCEPROP 2 LAST ROOM PVCCIN_CPU0_PWR_VR
J 0
(275 1400);
DISPLAY 1.936170 (275 1400);
PAINT ORANGE (275 1400);
DISPLAY INVISIBLE (275 1400);
FORCEPROP 2 LAST BOM_COST PROC_VRD_VCCIN_CPU0
J 0
(450 1400);
DISPLAY 1.446809 (450 1400);
PAINT MONO (450 1400);
DISPLAY INVISIBLE (450 1400);
FORCEPROP 1 LAST SIZE 1B
J 0
(900 1275);
DISPLAY 1.723404 (900 1275);
PAINT GREEN (900 1275);
DISPLAY INVISIBLE (900 1275);
FORCEPROP 1 LAST VOLTAGE 0
J 0
(825 1325);
PAINT SKYBLUE (825 1325);
DISPLAY INVISIBLE (825 1325);
FORCEPROP 1 LAST HDL_POWER GND
J 0
(825 1475);
DISPLAY 1.723404 (825 1475);
PAINT GREEN (825 1475);
DISPLAY INVISIBLE (825 1475);
FORCEADD CAP..1
(2600 -25);
FORCEPROP 1 LAST PACK_TYPE 0402LF
J 0
(2650 -225);
DISPLAY 0.617021 (2650 -225);
PAINT SKYBLUE (2650 -225);
FORCEPROP 1 LAST MATERIAL X7R
J 0
(2650 -125);
DISPLAY 0.617021 (2650 -125);
PAINT SKYBLUE (2650 -125);
FORCEPROP 1 LAST TOLERANCE 10%
J 0
(2650 -75);
DISPLAY 0.617021 (2650 -75);
PAINT SKYBLUE (2650 -75);
FORCEPROP 1 LAST VOLTAGE 50V
J 0
(2650 -25);
DISPLAY 0.617021 (2650 -25);
PAINT SKYBLUE (2650 -25);
FORCEPROP 1 LAST LOCATION CT48
J 0
(2500 25);
DISPLAY 0.617021 (2500 25);
PAINT AQUA (2500 25);
FORCEPROP 0 LAST STATUS NOPOP
J 0
(2650 75);
DISPLAY 1.021277 (2650 75);
PAINT ORANGE (2650 75);
FORCEPROP 1 LAST VALUE 1000PF
J 0
(2650 25);
DISPLAY 0.617021 (2650 25);
PAINT SKYBLUE (2650 25);
FORCEPROP 1 LAST PART_NUMBER A36096-046
J 0
(2650 -175);
DISPLAY 0.617021 (2650 -175);
PAINT BLUE (2650 -175);
FORCEPROP 1 LASTPIN (2600 75) $PN 1
J 0
(2610 55);
DISPLAY 0.787234 (2610 55);
PAINT ORANGE (2610 55);
DISPLAY INVISIBLE (2610 55);
FORCEPROP 1 LASTPIN (2600 -125) $PN 2
J 0
(2610 -145);
DISPLAY 0.787234 (2610 -145);
PAINT ORANGE (2610 -145);
DISPLAY INVISIBLE (2610 -145);
FORCEPROP 2 LAST CDS_LIB mstr_discrete
J 0
(2600 -25);
PAINT MONO (2600 -25);
DISPLAY INVISIBLE (2600 -25);
FORCEPROP 1 LAST PATH I119
J 0
(2650 125);
DISPLAY 0.978723 (2650 125);
PAINT WHITE (2650 125);
DISPLAY INVISIBLE (2650 125);
FORCEPROP 0 LAST ROOM VDDQ_KLM_PWR_VR
J 0
(2650 175);
DISPLAY 1.021277 (2650 175);
PAINT ORANGE (2650 175);
DISPLAY INVISIBLE (2650 175);
FORCEADD GND..1
(2600 -225);
FORCEPROP 3 LASTPIN (2600 -175) SIG_NAME GND\g
J 0
(2610 -165);
DISPLAY 0.659574 (2610 -165);
PAINT MONO (2610 -165);
DISPLAY INVISIBLE (2610 -165);
FORCEPROP 2 LAST CDS_LIB mstr_symbols
J 0
(2600 -225);
PAINT MONO (2600 -225);
DISPLAY INVISIBLE (2600 -225);
FORCEPROP 1 LAST PATH I120
J 0
(2675 -225);
DISPLAY 0.872340 (2675 -225);
PAINT AQUA (2675 -225);
DISPLAY INVISIBLE (2675 -225);
FORCEPROP 1 LAST HDL_POWER GND
J 0
(2600 -75);
DISPLAY 1.170213 (2600 -75);
PAINT GREEN (2600 -75);
DISPLAY INVISIBLE (2600 -75);
FORCEPROP 1 LAST SIZE 1B
J 0
(2675 -275);
DISPLAY 1.170213 (2675 -275);
PAINT AQUA (2675 -275);
DISPLAY INVISIBLE (2675 -275);
FORCEPROP 1 LAST BODY_TYPE PLUMBING
J 0
(2555 -268);
DISPLAY 0.340426 (2555 -268);
PAINT GREEN (2555 -268);
DISPLAY INVISIBLE (2555 -268);
FORCEPROP 1 LAST VOLTAGE 0
J 0
(2600 -225);
PAINT SKYBLUE (2600 -225);
DISPLAY INVISIBLE (2600 -225);
FORCEPROP 2 LAST ROOM VDDQ_KLM_PWR_VR
J 0
(2025 -150);
DISPLAY 1.361702 (2025 -150);
PAINT ORANGE (2025 -150);
DISPLAY INVISIBLE (2025 -150);
FORCEADD SC2K2P50V3KX-GP..1
(2675 -525);
FORCEPROP 1 LAST LOCATION CT47
J 0
(2700 -495);
DISPLAY 0.617021 (2700 -495);
PAINT GREEN (2700 -495);
FORCEPROP 1 LAST VALUE SC2K2P50V3KX-GP
J 0
(2700 -575);
DISPLAY 0.617021 (2700 -575);
PAINT GREEN (2700 -575);
FORCEPROP 0 LAST STATUS NOPOP
J 0
(2725 -450);
DISPLAY 1.021277 (2725 -450);
PAINT ORANGE (2725 -450);
FORCEPROP 1 LAST CDS_LMAN_SYM_OUTLINE -50,25,50,-25
J 0
(2675 -525);
DISPLAY 0.468085 (2675 -525);
PAINT GREEN (2675 -525);
DISPLAY INVISIBLE (2675 -525);
FORCEPROP 2 LAST CDS_LIB w_hdl
J 0
(2675 -525);
PAINT MONO (2675 -525);
DISPLAY INVISIBLE (2675 -525);
FORCEPROP 1 LAST PATH I121
J 0
(2675 -525);
DISPLAY 0.617021 (2675 -525);
PAINT GREEN (2675 -525);
DISPLAY INVISIBLE (2675 -525);
FORCEPROP 1 LAST PACK_TYPE SMD-BCG6
J 0
(2675 -525);
DISPLAY 0.617021 (2675 -525);
PAINT GREEN (2675 -525);
DISPLAY INVISIBLE (2675 -525);
FORCEPROP 1 LAST PART_NUMBER 78.22224.2BL
J 0
(2675 -525);
DISPLAY 0.617021 (2675 -525);
PAINT GREEN (2675 -525);
DISPLAY INVISIBLE (2675 -525);
FORCEADD GND..1
(2675 -1100);
FORCEPROP 3 LASTPIN (2675 -1050) SIG_NAME GND\g
J 0
(2685 -1040);
DISPLAY 0.659574 (2685 -1040);
PAINT MONO (2685 -1040);
DISPLAY INVISIBLE (2685 -1040);
FORCEPROP 2 LAST CDS_LIB mstr_symbols
J 0
(2675 -1100);
PAINT MONO (2675 -1100);
DISPLAY INVISIBLE (2675 -1100);
FORCEPROP 1 LAST PATH I122
J 0
(2750 -1100);
DISPLAY 0.872340 (2750 -1100);
PAINT AQUA (2750 -1100);
DISPLAY INVISIBLE (2750 -1100);
FORCEPROP 2 LAST ROOM PVCCIN_CPU0_PWR_VR
J 0
(2125 -1025);
DISPLAY 1.936170 (2125 -1025);
PAINT ORANGE (2125 -1025);
DISPLAY INVISIBLE (2125 -1025);
FORCEPROP 2 LAST BOM_COST PROC_VRD_VCCIN_CPU0
J 0
(2300 -1025);
DISPLAY 1.446809 (2300 -1025);
PAINT MONO (2300 -1025);
DISPLAY INVISIBLE (2300 -1025);
FORCEPROP 1 LAST BODY_TYPE PLUMBING
J 0
(2630 -1143);
DISPLAY 0.340426 (2630 -1143);
PAINT GREEN (2630 -1143);
DISPLAY INVISIBLE (2630 -1143);
FORCEPROP 1 LAST VOLTAGE 0
J 0
(2675 -1100);
PAINT SKYBLUE (2675 -1100);
DISPLAY INVISIBLE (2675 -1100);
FORCEPROP 1 LAST SIZE 1B
J 0
(2750 -1150);
DISPLAY 1.723404 (2750 -1150);
PAINT GREEN (2750 -1150);
DISPLAY INVISIBLE (2750 -1150);
FORCEPROP 1 LAST HDL_POWER GND
J 0
(2675 -950);
DISPLAY 1.723404 (2675 -950);
PAINT GREEN (2675 -950);
DISPLAY INVISIBLE (2675 -950);
FORCEADD 3D01R5F-GP..1
R 4
(2675 -850);
FORCEPROP 0 LAST STATUS NOPOP
J 0
(2725 -800);
DISPLAY 1.021277 (2725 -800);
PAINT ORANGE (2725 -800);
FORCEPROP 1 LAST LOCATION RT32
J 0
(2750 -855);
DISPLAY 0.617021 (2750 -855);
PAINT GREEN (2750 -855);
FORCEPROP 1 LAST VALUE 3D01R5F-GP
J 0
(2725 -900);
DISPLAY 0.617021 (2725 -900);
PAINT GREEN (2725 -900);
FORCEPROP 1 LAST CDS_LMAN_SYM_OUTLINE -50,75,50,-75
R 2
J 0
(2675 -850);
DISPLAY 0.468085 (2675 -850);
PAINT GREEN (2675 -850);
DISPLAY INVISIBLE (2675 -850);
FORCEPROP 1 LAST PATH I123
R 2
J 0
(2675 -850);
DISPLAY 0.617021 (2675 -850);
PAINT GREEN (2675 -850);
DISPLAY INVISIBLE (2675 -850);
FORCEPROP 2 LAST CDS_LIB w_hdl
J 0
(2675 -850);
PAINT MONO (2675 -850);
DISPLAY INVISIBLE (2675 -850);
FORCEPROP 1 LAST PART_NUMBER 64.3R015.16L
R 2
J 0
(2675 -850);
DISPLAY 0.617021 (2675 -850);
PAINT GREEN (2675 -850);
DISPLAY INVISIBLE (2675 -850);
FORCEPROP 1 LAST PACK_TYPE SMD-RG5
R 2
J 0
(2675 -850);
DISPLAY 0.617021 (2675 -850);
PAINT GREEN (2675 -850);
DISPLAY INVISIBLE (2675 -850);
FORCEPROP 2 LASTPIN (2675 -725) SIG_NAME UN$219$3D01R5F-GP$I123$2
J 0
(2685 -715);
DISPLAY 0.659574 (2685 -715);
PAINT MONO (2685 -715);
DISPLAY INVISIBLE (2685 -715);
FORCEADD CAP..1
(2700 2075);
FORCEPROP 1 LAST PACK_TYPE 0402LF
J 0
(2750 1875);
DISPLAY 0.617021 (2750 1875);
PAINT SKYBLUE (2750 1875);
FORCEPROP 1 LAST VALUE 1000PF
J 0
(2750 2125);
DISPLAY 0.617021 (2750 2125);
PAINT SKYBLUE (2750 2125);
FORCEPROP 1 LAST VOLTAGE 50V
J 0
(2750 2075);
DISPLAY 0.617021 (2750 2075);
PAINT SKYBLUE (2750 2075);
FORCEPROP 1 LAST TOLERANCE 10%
J 0
(2750 2025);
DISPLAY 0.617021 (2750 2025);
PAINT SKYBLUE (2750 2025);
FORCEPROP 1 LAST MATERIAL X7R
J 0
(2750 1975);
DISPLAY 0.617021 (2750 1975);
PAINT SKYBLUE (2750 1975);
FORCEPROP 1 LAST PART_NUMBER A36096-046
J 0
(2750 1925);
DISPLAY 0.617021 (2750 1925);
PAINT BLUE (2750 1925);
FORCEPROP 0 LAST STATUS NOPOP
J 0
(2475 2000);
DISPLAY 1.021277 (2475 2000);
PAINT ORANGE (2475 2000);
FORCEPROP 1 LAST LOCATION CT43
J 0
(2550 2075);
DISPLAY 0.617021 (2550 2075);
PAINT AQUA (2550 2075);
FORCEPROP 1 LASTPIN (2700 2175) $PN 1
J 0
(2710 2155);
DISPLAY 0.787234 (2710 2155);
PAINT ORANGE (2710 2155);
DISPLAY INVISIBLE (2710 2155);
FORCEPROP 1 LASTPIN (2700 1975) $PN 2
J 0
(2710 1955);
DISPLAY 0.787234 (2710 1955);
PAINT ORANGE (2710 1955);
DISPLAY INVISIBLE (2710 1955);
FORCEPROP 0 LAST ROOM VDDQ_KLM_PWR_VR
J 0
(2750 2275);
DISPLAY 1.021277 (2750 2275);
PAINT ORANGE (2750 2275);
DISPLAY INVISIBLE (2750 2275);
FORCEPROP 1 LAST PATH I124
J 0
(2750 2225);
DISPLAY 0.978723 (2750 2225);
PAINT WHITE (2750 2225);
DISPLAY INVISIBLE (2750 2225);
FORCEPROP 2 LAST CDS_LIB mstr_discrete
J 0
(2700 2075);
PAINT MONO (2700 2075);
DISPLAY INVISIBLE (2700 2075);
FORCEADD GND..1
(2700 1875);
FORCEPROP 3 LASTPIN (2700 1925) SIG_NAME GND\g
J 0
(2710 1935);
DISPLAY 0.659574 (2710 1935);
PAINT MONO (2710 1935);
DISPLAY INVISIBLE (2710 1935);
FORCEPROP 1 LAST HDL_POWER GND
J 0
(2700 2025);
DISPLAY 1.170213 (2700 2025);
PAINT GREEN (2700 2025);
DISPLAY INVISIBLE (2700 2025);
FORCEPROP 1 LAST SIZE 1B
J 0
(2775 1825);
DISPLAY 1.170213 (2775 1825);
PAINT AQUA (2775 1825);
DISPLAY INVISIBLE (2775 1825);
FORCEPROP 1 LAST BODY_TYPE PLUMBING
J 0
(2655 1832);
DISPLAY 0.340426 (2655 1832);
PAINT GREEN (2655 1832);
DISPLAY INVISIBLE (2655 1832);
FORCEPROP 1 LAST VOLTAGE 0
J 0
(2700 1875);
PAINT SKYBLUE (2700 1875);
DISPLAY INVISIBLE (2700 1875);
FORCEPROP 2 LAST ROOM VDDQ_KLM_PWR_VR
J 0
(2125 1950);
DISPLAY 1.361702 (2125 1950);
PAINT ORANGE (2125 1950);
DISPLAY INVISIBLE (2125 1950);
FORCEPROP 1 LAST PATH I125
J 0
(2775 1875);
DISPLAY 0.872340 (2775 1875);
PAINT AQUA (2775 1875);
DISPLAY INVISIBLE (2775 1875);
FORCEPROP 2 LAST CDS_LIB mstr_symbols
J 0
(2700 1875);
PAINT MONO (2700 1875);
DISPLAY INVISIBLE (2700 1875);
FORCEADD 3D01R5F-GP..1
R 4
(2800 1325);
FORCEPROP 1 LAST VALUE 3D01R5F-GP
J 0
(2575 1275);
DISPLAY 0.617021 (2575 1275);
PAINT GREEN (2575 1275);
FORCEPROP 1 LAST LOCATION RT29
J 0
(2675 1320);
DISPLAY 0.617021 (2675 1320);
PAINT GREEN (2675 1320);
FORCEPROP 0 LAST STATUS NOPOP
J 0
(2825 1275);
DISPLAY 1.021277 (2825 1275);
PAINT ORANGE (2825 1275);
FORCEPROP 1 LAST CDS_LMAN_SYM_OUTLINE -50,75,50,-75
R 2
J 0
(2800 1325);
DISPLAY 0.468085 (2800 1325);
PAINT GREEN (2800 1325);
DISPLAY INVISIBLE (2800 1325);
FORCEPROP 1 LAST PATH I126
R 2
J 0
(2800 1325);
DISPLAY 0.617021 (2800 1325);
PAINT GREEN (2800 1325);
DISPLAY INVISIBLE (2800 1325);
FORCEPROP 2 LAST CDS_LIB w_hdl
J 0
(2800 1325);
PAINT MONO (2800 1325);
DISPLAY INVISIBLE (2800 1325);
FORCEPROP 1 LAST PART_NUMBER 64.3R015.16L
R 2
J 0
(2800 1325);
DISPLAY 0.617021 (2800 1325);
PAINT GREEN (2800 1325);
DISPLAY INVISIBLE (2800 1325);
FORCEPROP 1 LAST PACK_TYPE SMD-RG5
R 2
J 0
(2800 1325);
DISPLAY 0.617021 (2800 1325);
PAINT GREEN (2800 1325);
DISPLAY INVISIBLE (2800 1325);
FORCEPROP 2 LASTPIN (2800 1450) SIG_NAME UN$219$3D01R5F-GP$I126$2
J 0
(2810 1460);
DISPLAY 0.659574 (2810 1460);
PAINT MONO (2810 1460);
DISPLAY INVISIBLE (2810 1460);
FORCEADD SC2K2P50V3KX-GP..1
(2800 1625);
FORCEPROP 1 LAST LOCATION CT44
J 0
(2825 1655);
DISPLAY 0.617021 (2825 1655);
PAINT GREEN (2825 1655);
FORCEPROP 0 LAST STATUS NOPOP
J 0
(2850 1525);
DISPLAY 1.021277 (2850 1525);
PAINT ORANGE (2850 1525);
FORCEPROP 1 LAST VALUE SC2K2P50V3KX-GP
J 0
(2825 1575);
DISPLAY 0.617021 (2825 1575);
PAINT GREEN (2825 1575);
FORCEPROP 2 LAST CDS_LIB w_hdl
J 0
(2800 1625);
PAINT MONO (2800 1625);
DISPLAY INVISIBLE (2800 1625);
FORCEPROP 1 LAST CDS_LMAN_SYM_OUTLINE -50,25,50,-25
J 0
(2800 1625);
DISPLAY 0.468085 (2800 1625);
PAINT GREEN (2800 1625);
DISPLAY INVISIBLE (2800 1625);
FORCEPROP 1 LAST PATH I127
J 0
(2800 1625);
DISPLAY 0.617021 (2800 1625);
PAINT GREEN (2800 1625);
DISPLAY INVISIBLE (2800 1625);
FORCEPROP 1 LAST PART_NUMBER 78.22224.2BL
J 0
(2800 1625);
DISPLAY 0.617021 (2800 1625);
PAINT GREEN (2800 1625);
DISPLAY INVISIBLE (2800 1625);
FORCEPROP 1 LAST PACK_TYPE SMD-BCG6
J 0
(2800 1625);
DISPLAY 0.617021 (2800 1625);
PAINT GREEN (2800 1625);
DISPLAY INVISIBLE (2800 1625);
FORCEADD GND..1
(2800 1100);
FORCEPROP 3 LASTPIN (2800 1150) SIG_NAME GND\g
J 0
(2810 1160);
DISPLAY 0.659574 (2810 1160);
PAINT MONO (2810 1160);
DISPLAY INVISIBLE (2810 1160);
FORCEPROP 2 LAST CDS_LIB mstr_symbols
J 0
(2800 1100);
PAINT MONO (2800 1100);
DISPLAY INVISIBLE (2800 1100);
FORCEPROP 1 LAST PATH I128
J 0
(2875 1100);
DISPLAY 0.872340 (2875 1100);
PAINT AQUA (2875 1100);
DISPLAY INVISIBLE (2875 1100);
FORCEPROP 2 LAST ROOM PVCCIN_CPU0_PWR_VR
J 0
(2250 1175);
DISPLAY 1.936170 (2250 1175);
PAINT ORANGE (2250 1175);
DISPLAY INVISIBLE (2250 1175);
FORCEPROP 2 LAST BOM_COST PROC_VRD_VCCIN_CPU0
J 0
(2425 1175);
DISPLAY 1.446809 (2425 1175);
PAINT MONO (2425 1175);
DISPLAY INVISIBLE (2425 1175);
FORCEPROP 1 LAST BODY_TYPE PLUMBING
J 0
(2755 1057);
DISPLAY 0.340426 (2755 1057);
PAINT GREEN (2755 1057);
DISPLAY INVISIBLE (2755 1057);
FORCEPROP 1 LAST VOLTAGE 0
J 0
(2800 1100);
PAINT SKYBLUE (2800 1100);
DISPLAY INVISIBLE (2800 1100);
FORCEPROP 1 LAST SIZE 1B
J 0
(2875 1050);
DISPLAY 1.723404 (2875 1050);
PAINT GREEN (2875 1050);
DISPLAY INVISIBLE (2875 1050);
FORCEPROP 1 LAST HDL_POWER GND
J 0
(2800 1250);
DISPLAY 1.723404 (2800 1250);
PAINT GREEN (2800 1250);
DISPLAY INVISIBLE (2800 1250);
FORCEADD RES..1
(-350 1850);
FORCEPROP 1 LAST WATTAGE 1/16W
J 2
(-375 1700);
DISPLAY 0.617021 (-375 1700);
PAINT SKYBLUE (-375 1700);
FORCEPROP 1 LAST MATERIAL CHIP
J 0
(-350 1700);
DISPLAY 0.617021 (-350 1700);
PAINT SKYBLUE (-350 1700);
FORCEPROP 1 LAST TOLERANCE 5%
J 0
(-350 1750);
DISPLAY 0.617021 (-350 1750);
PAINT SKYBLUE (-350 1750);
FORCEPROP 1 LAST VALUE 0.0
J 2
(-375 1750);
DISPLAY 0.617021 (-375 1750);
PAINT SKYBLUE (-375 1750);
FORCEPROP 1 LAST LOCATION RT30
J 0
(-400 1875);
DISPLAY 0.617021 (-400 1875);
PAINT AQUA (-400 1875);
FORCEPROP 1 LAST PART_NUMBER G21497-005
J 0
(-450 1800);
DISPLAY 0.617021 (-450 1800);
PAINT BLUE (-450 1800);
FORCEPROP 1 LAST PACK_TYPE 0402
J 0
(-250 1700);
DISPLAY 0.617021 (-250 1700);
PAINT SKYBLUE (-250 1700);
FORCEPROP 2 LAST BOM_COST DEBUG
J 0
(-400 2050);
DISPLAY 1.021277 (-400 2050);
PAINT ORANGE (-400 2050);
DISPLAY INVISIBLE (-400 2050);
FORCEPROP 2 LAST ROOM BMC_DEBUG_HEADER
J 0
(-400 2000);
DISPLAY 1.021277 (-400 2000);
PAINT ORANGE (-400 2000);
DISPLAY INVISIBLE (-400 2000);
FORCEPROP 1 LAST PATH I129
J 0
(-400 2000);
DISPLAY 0.978723 (-400 2000);
PAINT WHITE (-400 2000);
DISPLAY INVISIBLE (-400 2000);
FORCEPROP 2 LAST CDS_LIB mstr_discrete
J 0
(-350 1850);
PAINT MONO (-350 1850);
DISPLAY INVISIBLE (-350 1850);
FORCEPROP 1 LASTPIN (-450 1850) $PN 1
J 0
(-438 1862);
DISPLAY 0.787234 (-438 1862);
PAINT ORANGE (-438 1862);
DISPLAY INVISIBLE (-438 1862);
FORCEPROP 1 LASTPIN (-250 1850) $PN 2
J 0
(-288 1862);
DISPLAY 0.787234 (-288 1862);
PAINT ORANGE (-288 1862);
DISPLAY INVISIBLE (-288 1862);
FORCEADD RES..1
(-100 -275);
FORCEPROP 1 LAST LOCATION RT31
J 0
(-150 -250);
DISPLAY 0.617021 (-150 -250);
PAINT AQUA (-150 -250);
FORCEPROP 1 LAST PART_NUMBER G21497-005
J 0
(-200 -325);
DISPLAY 0.617021 (-200 -325);
PAINT BLUE (-200 -325);
FORCEPROP 1 LAST VALUE 0.0
J 2
(-125 -375);
DISPLAY 0.617021 (-125 -375);
PAINT SKYBLUE (-125 -375);
FORCEPROP 1 LAST TOLERANCE 5%
J 0
(-100 -375);
DISPLAY 0.617021 (-100 -375);
PAINT SKYBLUE (-100 -375);
FORCEPROP 1 LAST MATERIAL CHIP
J 0
(-100 -425);
DISPLAY 0.617021 (-100 -425);
PAINT SKYBLUE (-100 -425);
FORCEPROP 1 LAST PACK_TYPE 0402
J 0
(0 -425);
DISPLAY 0.617021 (0 -425);
PAINT SKYBLUE (0 -425);
FORCEPROP 1 LAST WATTAGE 1/16W
J 2
(-125 -425);
DISPLAY 0.617021 (-125 -425);
PAINT SKYBLUE (-125 -425);
FORCEPROP 2 LAST CDS_LIB mstr_discrete
J 0
(-100 -275);
PAINT MONO (-100 -275);
DISPLAY INVISIBLE (-100 -275);
FORCEPROP 1 LAST PATH I130
J 0
(-150 -125);
DISPLAY 0.978723 (-150 -125);
PAINT WHITE (-150 -125);
DISPLAY INVISIBLE (-150 -125);
FORCEPROP 2 LAST ROOM BMC_DEBUG_HEADER
J 0
(-150 -125);
DISPLAY 1.021277 (-150 -125);
PAINT ORANGE (-150 -125);
DISPLAY INVISIBLE (-150 -125);
FORCEPROP 2 LAST BOM_COST DEBUG
J 0
(-150 -75);
DISPLAY 1.021277 (-150 -75);
PAINT ORANGE (-150 -75);
DISPLAY INVISIBLE (-150 -75);
FORCEPROP 1 LASTPIN (-200 -275) $PN 1
J 0
(-188 -263);
DISPLAY 0.787234 (-188 -263);
PAINT ORANGE (-188 -263);
DISPLAY INVISIBLE (-188 -263);
FORCEPROP 1 LASTPIN (0 -275) $PN 2
J 0
(-38 -263);
DISPLAY 0.787234 (-38 -263);
PAINT ORANGE (-38 -263);
DISPLAY INVISIBLE (-38 -263);
FORCEADD GND..1
(2400 1325);
FORCEPROP 3 LASTPIN (2400 1375) SIG_NAME GND\g
J 0
(2410 1385);
DISPLAY 0.659574 (2410 1385);
PAINT MONO (2410 1385);
DISPLAY INVISIBLE (2410 1385);
FORCEPROP 2 LAST ROOM VDDQ_DEF_PWR_VR
J 0
(1850 1400);
DISPLAY 1.936170 (1850 1400);
PAINT ORANGE (1850 1400);
DISPLAY INVISIBLE (1850 1400);
FORCEPROP 2 LAST BOM_COST PROC_VRD_VCCIN_CPU0
J 0
(2025 1400);
DISPLAY 1.446809 (2025 1400);
PAINT MONO (2025 1400);
DISPLAY INVISIBLE (2025 1400);
FORCEPROP 1 LAST SIZE 1B
J 0
(2475 1275);
DISPLAY 1.723404 (2475 1275);
PAINT GREEN (2475 1275);
DISPLAY INVISIBLE (2475 1275);
FORCEPROP 1 LAST BODY_TYPE PLUMBING
J 0
(2355 1282);
DISPLAY 0.340426 (2355 1282);
PAINT GREEN (2355 1282);
DISPLAY INVISIBLE (2355 1282);
FORCEPROP 2 LAST CDS_LIB mstr_symbols
J 0
(2400 1325);
DISPLAY 1.936170 (2400 1325);
PAINT ORANGE (2400 1325);
DISPLAY INVISIBLE (2400 1325);
FORCEPROP 1 LAST VOLTAGE 0
J 0
(2400 1325);
PAINT SKYBLUE (2400 1325);
DISPLAY INVISIBLE (2400 1325);
FORCEPROP 1 LAST PATH I19
J 0
(2475 1325);
DISPLAY 0.893617 (2475 1325);
PAINT AQUA (2475 1325);
DISPLAY INVISIBLE (2475 1325);
FORCEPROP 1 LAST HDL_POWER GND
J 0
(2400 1475);
DISPLAY 1.723404 (2400 1475);
PAINT GREEN (2400 1475);
DISPLAY INVISIBLE (2400 1475);
FORCEADD OFFPAGE..2
(3600 2625);
FORCEPROP 2 LAST $XR0 218 
J 0
(3789 2625);
DISPLAY 0.638298 (3789 2625);
PAINT MONO (3789 2625);
FORCEPROP 1 LAST COMMENT_BODY TRUE
J 0
(3555 2530);
DISPLAY 1.723404 (3555 2530);
PAINT GREEN (3555 2530);
DISPLAY INVISIBLE (3555 2530);
FORCEPROP 2 LAST ROOM VDDQ_DEF_PWR_VR
J 0
(3200 2700);
DISPLAY 1.936170 (3200 2700);
PAINT ORANGE (3200 2700);
DISPLAY INVISIBLE (3200 2700);
FORCEPROP 1 LAST OFFPAGE TRUE
J 0
(3925 2500);
DISPLAY 1.723404 (3925 2500);
PAINT GREEN (3925 2500);
DISPLAY INVISIBLE (3925 2500);
FORCEPROP 2 LAST CDS_LIB mstr_standard
J 0
(3600 2625);
DISPLAY 1.936170 (3600 2625);
PAINT ORANGE (3600 2625);
DISPLAY INVISIBLE (3600 2625);
FORCEPROP 2 LAST PATH I3
J 0
(3790 2675);
DISPLAY 1.021277 (3790 2675);
PAINT ORANGE (3790 2675);
DISPLAY INVISIBLE (3790 2675);
FORCEPROP 2 LAST BOM_COST PROC_VRD_VCCIN_CPU0
J 0
(3800 2675);
DISPLAY 1.446809 (3800 2675);
PAINT MONO (3800 2675);
DISPLAY INVISIBLE (3800 2675);
FORCEADD OFFPAGE..1
(-1700 1975);
FORCEPROP 2 LAST $XR0 218 
J 0
(-1952 1975);
DISPLAY 0.638298 (-1952 1975);
PAINT MONO (-1952 1975);
FORCEPROP 2 LASTPIN (-1650 1975) SIG_NAME VR_PVDDQ_DEF_PWM1
J 0
(-1635 1985);
DISPLAY 0.617021 (-1635 1985);
PAINT ORANGE (-1635 1985);
FORCEPROP 2 LAST ROOM VDDQ_DEF_PWR_VR
J 0
(-2100 2050);
DISPLAY 1.936170 (-2100 2050);
PAINT ORANGE (-2100 2050);
DISPLAY INVISIBLE (-2100 2050);
FORCEPROP 1 LAST COMMENT_BODY TRUE
J 0
(-1575 1875);
DISPLAY 1.680851 (-1575 1875);
PAINT GREEN (-1575 1875);
DISPLAY INVISIBLE (-1575 1875);
FORCEPROP 1 LAST OFFPAGE TRUE
J 0
(-1375 1850);
DISPLAY 1.680851 (-1375 1850);
PAINT GREEN (-1375 1850);
DISPLAY INVISIBLE (-1375 1850);
FORCEPROP 2 LAST PATH I33
J 0
(-1980 2025);
DISPLAY 1.021277 (-1980 2025);
PAINT ORANGE (-1980 2025);
DISPLAY INVISIBLE (-1980 2025);
FORCEPROP 2 LAST CDS_LIB mstr_standard
J 0
(-1700 1975);
DISPLAY 1.936170 (-1700 1975);
PAINT ORANGE (-1700 1975);
DISPLAY INVISIBLE (-1700 1975);
FORCEPROP 2 LAST BOM_COST PROC_VRD_VCCIN_CPU0
J 0
(-1950 2025);
DISPLAY 1.446809 (-1950 2025);
PAINT MONO (-1950 2025);
DISPLAY INVISIBLE (-1950 2025);
FORCEADD GND..1
(-2500 1950);
FORCEPROP 3 LASTPIN (-2500 2000) SIG_NAME GND\g
J 0
(-2490 2010);
DISPLAY 0.659574 (-2490 2010);
PAINT MONO (-2490 2010);
DISPLAY INVISIBLE (-2490 2010);
FORCEPROP 1 LAST PATH I35
J 0
(-2425 1950);
DISPLAY 0.893617 (-2425 1950);
PAINT AQUA (-2425 1950);
DISPLAY INVISIBLE (-2425 1950);
FORCEPROP 1 LAST BODY_TYPE PLUMBING
J 0
(-2545 1907);
DISPLAY 0.340426 (-2545 1907);
PAINT GREEN (-2545 1907);
DISPLAY INVISIBLE (-2545 1907);
FORCEPROP 1 LAST SIZE 1B
J 0
(-2425 1900);
DISPLAY 1.723404 (-2425 1900);
PAINT GREEN (-2425 1900);
DISPLAY INVISIBLE (-2425 1900);
FORCEPROP 2 LAST CDS_LIB mstr_symbols
J 0
(-2500 1950);
DISPLAY 1.936170 (-2500 1950);
PAINT ORANGE (-2500 1950);
DISPLAY INVISIBLE (-2500 1950);
FORCEPROP 1 LAST VOLTAGE 0
J 0
(-2500 1950);
PAINT SKYBLUE (-2500 1950);
DISPLAY INVISIBLE (-2500 1950);
FORCEPROP 2 LAST ROOM VDDQ_DEF_PWR_VR
J 0
(-3050 2025);
DISPLAY 1.936170 (-3050 2025);
PAINT ORANGE (-3050 2025);
DISPLAY INVISIBLE (-3050 2025);
FORCEPROP 2 LAST BOM_COST PROC_VRD_VCCIN_CPU0
J 0
(-2875 2025);
DISPLAY 1.446809 (-2875 2025);
PAINT MONO (-2875 2025);
DISPLAY INVISIBLE (-2875 2025);
FORCEPROP 1 LAST HDL_POWER GND
J 0
(-2500 2100);
DISPLAY 1.723404 (-2500 2100);
PAINT GREEN (-2500 2100);
DISPLAY INVISIBLE (-2500 2100);
FORCEADD OFFPAGE..2
(3625 2950);
FORCEPROP 2 LAST $XR0 218 
J 0
(3814 2950);
DISPLAY 0.638298 (3814 2950);
PAINT MONO (3814 2950);
FORCEPROP 1 LAST COMMENT_BODY TRUE
J 0
(3580 2855);
DISPLAY 1.723404 (3580 2855);
PAINT GREEN (3580 2855);
DISPLAY INVISIBLE (3580 2855);
FORCEPROP 2 LAST CDS_LIB mstr_standard
J 2
(3625 2950);
DISPLAY 1.936170 (3625 2950);
PAINT ORANGE (3625 2950);
DISPLAY INVISIBLE (3625 2950);
FORCEPROP 2 LAST PATH I4
J 0
(3815 3000);
DISPLAY 1.021277 (3815 3000);
PAINT ORANGE (3815 3000);
DISPLAY INVISIBLE (3815 3000);
FORCEPROP 2 LAST BOM_COST PROC_VRD_VCCIN_CPU0
J 0
(3825 3000);
DISPLAY 1.446809 (3825 3000);
PAINT MONO (3825 3000);
DISPLAY INVISIBLE (3825 3000);
FORCEPROP 1 LAST OFFPAGE TRUE
J 0
(3950 2825);
DISPLAY 1.723404 (3950 2825);
PAINT GREEN (3950 2825);
DISPLAY INVISIBLE (3950 2825);
FORCEPROP 2 LAST ROOM VDDQ_DEF_PWR_VR
J 0
(3225 3025);
DISPLAY 1.936170 (3225 3025);
PAINT ORANGE (3225 3025);
DISPLAY INVISIBLE (3225 3025);
FORCEADD CAP..1
R 2
(-1300 1725);
FORCEPROP 1 LAST PACK_TYPE 0402
J 2
(-1350 1525);
DISPLAY 0.617021 (-1350 1525);
PAINT SKYBLUE (-1350 1525);
FORCEPROP 1 LAST PART_NUMBER A36096-104
J 2
(-1350 1575);
DISPLAY 0.617021 (-1350 1575);
PAINT BLUE (-1350 1575);
FORCEPROP 1 LAST MATERIAL X7R
J 2
(-1350 1625);
DISPLAY 0.617021 (-1350 1625);
PAINT SKYBLUE (-1350 1625);
FORCEPROP 1 LAST TOLERANCE 10%
J 2
(-1350 1675);
DISPLAY 0.617021 (-1350 1675);
PAINT SKYBLUE (-1350 1675);
FORCEPROP 1 LAST LOCATION C7A12
J 2
(-1350 1825);
DISPLAY 0.617021 (-1350 1825);
PAINT AQUA (-1350 1825);
FORCEPROP 1 LAST VALUE 0.220UF
J 2
(-1350 1775);
DISPLAY 0.617021 (-1350 1775);
PAINT SKYBLUE (-1350 1775);
FORCEPROP 1 LAST VOLTAGE 16V
J 2
(-1350 1725);
DISPLAY 0.617021 (-1350 1725);
PAINT SKYBLUE (-1350 1725);
FORCEPROP 1 LASTPIN (-1300 1625) $PN 2
J 2
(-1310 1605);
DISPLAY 0.617021 (-1310 1605);
PAINT ORANGE (-1310 1605);
DISPLAY INVISIBLE (-1310 1605);
FORCEPROP 2 LAST CDS_LIB mstr_discrete
J 0
(-1300 1725);
PAINT ORANGE (-1300 1725);
DISPLAY INVISIBLE (-1300 1725);
FORCEPROP 1 LASTPIN (-1300 1825) $PN 1
J 2
(-1310 1805);
DISPLAY 0.617021 (-1310 1805);
PAINT ORANGE (-1310 1805);
DISPLAY INVISIBLE (-1310 1805);
FORCEPROP 2 LAST CDS_SEC 1
J 0
(-1350 1925);
PAINT MONO (-1350 1925);
DISPLAY INVISIBLE (-1350 1925);
FORCEPROP 0 LAST SPOF TRUE
J 0
(-1350 1925);
DISPLAY 1.021277 (-1350 1925);
PAINT ORANGE (-1350 1925);
DISPLAY INVISIBLE (-1350 1925);
FORCEPROP 2 LAST CDS_LOCATION C7A12
J 2
(-1350 1825);
DISPLAY 0.617021 (-1350 1825);
PAINT AQUA (-1350 1825);
DISPLAY INVISIBLE (-1350 1825);
FORCEPROP 2 LAST $SEC 1
J 0
(-1350 1925);
PAINT MONO (-1350 1925);
DISPLAY INVISIBLE (-1350 1925);
FORCEPROP 2 LAST ROOM VDDQ_DEF_PWR_VR
J 0
(-1375 1875);
DISPLAY 1.361702 (-1375 1875);
PAINT ORANGE (-1375 1875);
DISPLAY INVISIBLE (-1375 1875);
FORCEPROP 1 LAST PATH I44
J 2
(-1350 1875);
DISPLAY 0.978723 (-1350 1875);
PAINT WHITE (-1350 1875);
DISPLAY INVISIBLE (-1350 1875);
FORCEADD CAP..1
(-2500 2400);
FORCEPROP 1 LAST PACK_TYPE 0805
J 0
(-2450 2200);
DISPLAY 0.617021 (-2450 2200);
PAINT SKYBLUE (-2450 2200);
FORCEPROP 1 LAST MATERIAL X6S
J 0
(-2450 2300);
DISPLAY 0.617021 (-2450 2300);
PAINT SKYBLUE (-2450 2300);
FORCEPROP 1 LAST VOLTAGE 16V
J 0
(-2450 2400);
DISPLAY 0.617021 (-2450 2400);
PAINT SKYBLUE (-2450 2400);
FORCEPROP 1 LAST TOLERANCE 10%
J 0
(-2450 2350);
DISPLAY 0.617021 (-2450 2350);
PAINT SKYBLUE (-2450 2350);
FORCEPROP 1 LAST VALUE 10UF
J 0
(-2450 2450);
DISPLAY 0.617021 (-2450 2450);
PAINT SKYBLUE (-2450 2450);
FORCEPROP 1 LAST LOCATION C3L2
J 0
(-2450 2500);
DISPLAY 0.617021 (-2450 2500);
PAINT AQUA (-2450 2500);
FORCEPROP 1 LAST PART_NUMBER C95333-007
J 0
(-2450 2250);
DISPLAY 0.617021 (-2450 2250);
PAINT BLUE (-2450 2250);
FORCEPROP 1 LASTPIN (-2500 2300) $PN 2
J 0
(-2490 2280);
DISPLAY 1.063830 (-2490 2280);
PAINT ORANGE (-2490 2280);
DISPLAY INVISIBLE (-2490 2280);
FORCEPROP 2 LAST CDS_LIB mstr_discrete
J 0
(-2500 2400);
PAINT ORANGE (-2500 2400);
DISPLAY INVISIBLE (-2500 2400);
FORCEPROP 2 LAST CDS_LOCATION C3L2
J 0
(-2450 2500);
DISPLAY 0.617021 (-2450 2500);
PAINT AQUA (-2450 2500);
DISPLAY INVISIBLE (-2450 2500);
FORCEPROP 1 LASTPIN (-2500 2500) $PN 1
J 0
(-2490 2480);
DISPLAY 1.063830 (-2490 2480);
PAINT ORANGE (-2490 2480);
DISPLAY INVISIBLE (-2490 2480);
FORCEPROP 2 LAST ROOM VDDQ_DEF_PWR_VR
J 0
(-2450 2550);
DISPLAY 1.361702 (-2450 2550);
PAINT ORANGE (-2450 2550);
DISPLAY INVISIBLE (-2450 2550);
FORCEPROP 1 LAST PATH I45
J 0
(-2450 2550);
DISPLAY 1.319149 (-2450 2550);
PAINT WHITE (-2450 2550);
DISPLAY INVISIBLE (-2450 2550);
FORCEPROP 2 LAST $SEC 1
J 0
(-2450 2625);
DISPLAY 0.680851 (-2450 2625);
PAINT MONO (-2450 2625);
DISPLAY INVISIBLE (-2450 2625);
FORCEPROP 2 LAST CDS_SEC 1
J 0
(-2450 2625);
DISPLAY 1.021277 (-2450 2625);
PAINT ORANGE (-2450 2625);
DISPLAY INVISIBLE (-2450 2625);
FORCEADD CAP..1
(-2250 2375);
FORCEPROP 1 LAST MATERIAL X6S
J 0
(-2200 2275);
DISPLAY 0.617021 (-2200 2275);
PAINT SKYBLUE (-2200 2275);
FORCEPROP 1 LAST PACK_TYPE 0805
J 0
(-2200 2175);
DISPLAY 0.617021 (-2200 2175);
PAINT SKYBLUE (-2200 2175);
FORCEPROP 1 LAST VOLTAGE 16V
J 0
(-2200 2375);
DISPLAY 0.617021 (-2200 2375);
PAINT SKYBLUE (-2200 2375);
FORCEPROP 1 LAST TOLERANCE 10%
J 0
(-2200 2325);
DISPLAY 0.617021 (-2200 2325);
PAINT SKYBLUE (-2200 2325);
FORCEPROP 1 LAST VALUE 10UF
J 0
(-2200 2425);
DISPLAY 0.617021 (-2200 2425);
PAINT SKYBLUE (-2200 2425);
FORCEPROP 1 LAST LOCATION C3L4
J 0
(-2200 2475);
DISPLAY 0.617021 (-2200 2475);
PAINT AQUA (-2200 2475);
FORCEPROP 1 LAST PART_NUMBER C95333-007
J 0
(-2200 2225);
DISPLAY 0.617021 (-2200 2225);
PAINT BLUE (-2200 2225);
FORCEPROP 1 LASTPIN (-2250 2275) $PN 2
J 0
(-2240 2255);
DISPLAY 1.063830 (-2240 2255);
PAINT ORANGE (-2240 2255);
DISPLAY INVISIBLE (-2240 2255);
FORCEPROP 2 LAST CDS_LIB mstr_discrete
J 0
(-2250 2375);
PAINT ORANGE (-2250 2375);
DISPLAY INVISIBLE (-2250 2375);
FORCEPROP 2 LAST CDS_LOCATION C3L4
J 0
(-2200 2475);
DISPLAY 0.617021 (-2200 2475);
PAINT AQUA (-2200 2475);
DISPLAY INVISIBLE (-2200 2475);
FORCEPROP 1 LASTPIN (-2250 2475) $PN 1
J 0
(-2240 2455);
DISPLAY 1.063830 (-2240 2455);
PAINT ORANGE (-2240 2455);
DISPLAY INVISIBLE (-2240 2455);
FORCEPROP 2 LAST ROOM VDDQ_DEF_PWR_VR
J 0
(-2200 2525);
DISPLAY 1.361702 (-2200 2525);
PAINT ORANGE (-2200 2525);
DISPLAY INVISIBLE (-2200 2525);
FORCEPROP 1 LAST PATH I46
J 0
(-2200 2525);
DISPLAY 1.319149 (-2200 2525);
PAINT WHITE (-2200 2525);
DISPLAY INVISIBLE (-2200 2525);
FORCEPROP 2 LAST $SEC 1
J 0
(-2200 2600);
DISPLAY 0.680851 (-2200 2600);
PAINT MONO (-2200 2600);
DISPLAY INVISIBLE (-2200 2600);
FORCEPROP 2 LAST CDS_SEC 1
J 0
(-2200 2600);
DISPLAY 1.021277 (-2200 2600);
PAINT ORANGE (-2200 2600);
DISPLAY INVISIBLE (-2200 2600);
FORCEADD CAP..1
(-2000 2375);
FORCEPROP 1 LAST MATERIAL X6S
J 0
(-1950 2275);
DISPLAY 0.617021 (-1950 2275);
PAINT SKYBLUE (-1950 2275);
FORCEPROP 1 LAST PACK_TYPE 0805
J 0
(-1950 2175);
DISPLAY 0.617021 (-1950 2175);
PAINT SKYBLUE (-1950 2175);
FORCEPROP 1 LAST VOLTAGE 16V
J 0
(-1950 2375);
DISPLAY 0.617021 (-1950 2375);
PAINT SKYBLUE (-1950 2375);
FORCEPROP 1 LAST TOLERANCE 10%
J 0
(-1950 2325);
DISPLAY 0.617021 (-1950 2325);
PAINT SKYBLUE (-1950 2325);
FORCEPROP 1 LAST VALUE 10UF
J 0
(-1950 2425);
DISPLAY 0.617021 (-1950 2425);
PAINT SKYBLUE (-1950 2425);
FORCEPROP 1 LAST LOCATION C3L13
J 0
(-1950 2475);
DISPLAY 0.617021 (-1950 2475);
PAINT AQUA (-1950 2475);
FORCEPROP 1 LAST PART_NUMBER C95333-007
J 0
(-1950 2225);
DISPLAY 0.617021 (-1950 2225);
PAINT BLUE (-1950 2225);
FORCEPROP 1 LASTPIN (-2000 2275) $PN 2
J 0
(-1990 2255);
DISPLAY 1.063830 (-1990 2255);
PAINT ORANGE (-1990 2255);
DISPLAY INVISIBLE (-1990 2255);
FORCEPROP 2 LAST CDS_LIB mstr_discrete
J 0
(-2000 2375);
PAINT ORANGE (-2000 2375);
DISPLAY INVISIBLE (-2000 2375);
FORCEPROP 2 LAST CDS_LOCATION C3L13
J 0
(-1950 2475);
DISPLAY 0.617021 (-1950 2475);
PAINT AQUA (-1950 2475);
DISPLAY INVISIBLE (-1950 2475);
FORCEPROP 1 LASTPIN (-2000 2475) $PN 1
J 0
(-1990 2455);
DISPLAY 1.063830 (-1990 2455);
PAINT ORANGE (-1990 2455);
DISPLAY INVISIBLE (-1990 2455);
FORCEPROP 2 LAST ROOM VDDQ_DEF_PWR_VR
J 0
(-1950 2525);
DISPLAY 1.361702 (-1950 2525);
PAINT ORANGE (-1950 2525);
DISPLAY INVISIBLE (-1950 2525);
FORCEPROP 1 LAST PATH I47
J 0
(-1950 2525);
DISPLAY 1.319149 (-1950 2525);
PAINT WHITE (-1950 2525);
DISPLAY INVISIBLE (-1950 2525);
FORCEPROP 2 LAST $SEC 1
J 0
(-1950 2600);
DISPLAY 0.680851 (-1950 2600);
PAINT MONO (-1950 2600);
DISPLAY INVISIBLE (-1950 2600);
FORCEPROP 2 LAST CDS_SEC 1
J 0
(-1950 2600);
DISPLAY 1.021277 (-1950 2600);
PAINT ORANGE (-1950 2600);
DISPLAY INVISIBLE (-1950 2600);
FORCEADD CAP..1
(-1725 2375);
FORCEPROP 1 LAST MATERIAL X6S
J 0
(-1675 2275);
DISPLAY 0.617021 (-1675 2275);
PAINT SKYBLUE (-1675 2275);
FORCEPROP 1 LAST VOLTAGE 16V
J 0
(-1675 2375);
DISPLAY 0.617021 (-1675 2375);
PAINT SKYBLUE (-1675 2375);
FORCEPROP 1 LAST TOLERANCE 10%
J 0
(-1675 2325);
DISPLAY 0.617021 (-1675 2325);
PAINT SKYBLUE (-1675 2325);
FORCEPROP 1 LAST VALUE 1.0UF
J 0
(-1675 2425);
DISPLAY 0.617021 (-1675 2425);
PAINT SKYBLUE (-1675 2425);
FORCEPROP 1 LAST PART_NUMBER D97712-011
J 0
(-1675 2225);
DISPLAY 0.617021 (-1675 2225);
PAINT BLUE (-1675 2225);
FORCEPROP 1 LAST LOCATION C7A11
J 0
(-1675 2475);
DISPLAY 0.617021 (-1675 2475);
PAINT AQUA (-1675 2475);
FORCEPROP 1 LAST PACK_TYPE 0402
J 0
(-1675 2175);
DISPLAY 0.617021 (-1675 2175);
PAINT SKYBLUE (-1675 2175);
FORCEPROP 1 LASTPIN (-1725 2275) $PN 2
J 0
(-1715 2255);
DISPLAY 1.063830 (-1715 2255);
PAINT ORANGE (-1715 2255);
DISPLAY INVISIBLE (-1715 2255);
FORCEPROP 2 LAST CDS_LIB mstr_discrete
J 0
(-1725 2375);
PAINT ORANGE (-1725 2375);
DISPLAY INVISIBLE (-1725 2375);
FORCEPROP 2 LAST CDS_LOCATION C7A11
J 0
(-1675 2475);
DISPLAY 0.617021 (-1675 2475);
PAINT AQUA (-1675 2475);
DISPLAY INVISIBLE (-1675 2475);
FORCEPROP 1 LASTPIN (-1725 2475) $PN 1
J 0
(-1715 2455);
DISPLAY 1.063830 (-1715 2455);
PAINT ORANGE (-1715 2455);
DISPLAY INVISIBLE (-1715 2455);
FORCEPROP 2 LAST ROOM VDDQ_DEF_PWR_VR
J 0
(-1675 2525);
DISPLAY 1.361702 (-1675 2525);
PAINT ORANGE (-1675 2525);
DISPLAY INVISIBLE (-1675 2525);
FORCEPROP 1 LAST PATH I48
J 0
(-1675 2525);
DISPLAY 1.319149 (-1675 2525);
PAINT WHITE (-1675 2525);
DISPLAY INVISIBLE (-1675 2525);
FORCEPROP 2 LAST $SEC 1
J 0
(-1675 2600);
DISPLAY 0.680851 (-1675 2600);
PAINT MONO (-1675 2600);
DISPLAY INVISIBLE (-1675 2600);
FORCEPROP 2 LAST CDS_SEC 1
J 0
(-1675 2600);
DISPLAY 1.021277 (-1675 2600);
PAINT ORANGE (-1675 2600);
DISPLAY INVISIBLE (-1675 2600);
FORCEADD CAP..1
(-1200 2350);
FORCEPROP 1 LAST MATERIAL X6S
J 0
(-1150 2250);
DISPLAY 0.617021 (-1150 2250);
PAINT SKYBLUE (-1150 2250);
FORCEPROP 1 LAST PACK_TYPE 0402
J 0
(-1150 2150);
DISPLAY 0.617021 (-1150 2150);
PAINT SKYBLUE (-1150 2150);
FORCEPROP 1 LAST VALUE 1.0UF
J 0
(-1150 2400);
DISPLAY 0.617021 (-1150 2400);
PAINT SKYBLUE (-1150 2400);
FORCEPROP 1 LAST LOCATION C7A16
J 0
(-1150 2450);
DISPLAY 0.617021 (-1150 2450);
PAINT AQUA (-1150 2450);
FORCEPROP 1 LAST PART_NUMBER D97712-011
J 0
(-1150 2200);
DISPLAY 0.617021 (-1150 2200);
PAINT BLUE (-1150 2200);
FORCEPROP 1 LAST TOLERANCE 10%
J 0
(-1150 2300);
DISPLAY 0.617021 (-1150 2300);
PAINT SKYBLUE (-1150 2300);
FORCEPROP 1 LAST VOLTAGE 16V
J 0
(-1150 2350);
DISPLAY 0.617021 (-1150 2350);
PAINT SKYBLUE (-1150 2350);
FORCEPROP 1 LASTPIN (-1200 2250) $PN 2
J 0
(-1190 2230);
DISPLAY 1.063830 (-1190 2230);
PAINT ORANGE (-1190 2230);
DISPLAY INVISIBLE (-1190 2230);
FORCEPROP 2 LAST CDS_LIB mstr_discrete
J 0
(-1200 2350);
PAINT ORANGE (-1200 2350);
DISPLAY INVISIBLE (-1200 2350);
FORCEPROP 2 LAST CDS_LOCATION C7A16
J 0
(-1150 2450);
DISPLAY 0.617021 (-1150 2450);
PAINT AQUA (-1150 2450);
DISPLAY INVISIBLE (-1150 2450);
FORCEPROP 1 LAST PATH I50
J 0
(-1150 2500);
DISPLAY 1.319149 (-1150 2500);
PAINT WHITE (-1150 2500);
DISPLAY INVISIBLE (-1150 2500);
FORCEPROP 2 LAST ROOM VDDQ_DEF_PWR_VR
J 0
(-1150 2500);
DISPLAY 1.361702 (-1150 2500);
PAINT ORANGE (-1150 2500);
DISPLAY INVISIBLE (-1150 2500);
FORCEPROP 1 LASTPIN (-1200 2450) $PN 1
J 0
(-1190 2430);
DISPLAY 1.063830 (-1190 2430);
PAINT ORANGE (-1190 2430);
DISPLAY INVISIBLE (-1190 2430);
FORCEPROP 2 LAST $SEC 1
J 0
(-1150 2575);
DISPLAY 0.680851 (-1150 2575);
PAINT MONO (-1150 2575);
DISPLAY INVISIBLE (-1150 2575);
FORCEPROP 2 LAST CDS_SEC 1
J 0
(-1150 2575);
DISPLAY 1.021277 (-1150 2575);
PAINT ORANGE (-1150 2575);
DISPLAY INVISIBLE (-1150 2575);
FORCEADD CAP_A..1
(-1475 2375);
FORCEPROP 1 LAST MATERIAL X7R
J 0
(-1425 2275);
DISPLAY 0.617021 (-1425 2275);
PAINT SKYBLUE (-1425 2275);
FORCEPROP 1 LAST VOLTAGE 16V
J 0
(-1425 2375);
DISPLAY 0.617021 (-1425 2375);
PAINT SKYBLUE (-1425 2375);
FORCEPROP 1 LAST TOLERANCE 10%
J 0
(-1425 2325);
DISPLAY 0.617021 (-1425 2325);
PAINT SKYBLUE (-1425 2325);
FORCEPROP 1 LAST PACK_TYPE 0402V
J 0
(-1425 2175);
DISPLAY 0.617021 (-1425 2175);
PAINT SKYBLUE (-1425 2175);
FORCEPROP 1 LAST VALUE 0.1UF
J 0
(-1425 2425);
DISPLAY 0.617021 (-1425 2425);
PAINT SKYBLUE (-1425 2425);
FORCEPROP 1 LAST PART_NUMBER A36096-030
J 0
(-1425 2225);
DISPLAY 0.617021 (-1425 2225);
PAINT BLUE (-1425 2225);
FORCEPROP 1 LAST LOCATION C7A5
J 0
(-1425 2475);
DISPLAY 0.617021 (-1425 2475);
PAINT AQUA (-1425 2475);
FORCEPROP 1 LASTPIN (-1475 2275) $PN 2
J 0
(-1465 2255);
DISPLAY 1.063830 (-1465 2255);
PAINT ORANGE (-1465 2255);
DISPLAY INVISIBLE (-1465 2255);
FORCEPROP 2 LAST CDS_LIB dev_discrete
J 0
(-1475 2375);
PAINT ORANGE (-1475 2375);
DISPLAY INVISIBLE (-1475 2375);
FORCEPROP 2 LAST CDS_LOCATION C7A5
J 0
(-1425 2475);
DISPLAY 0.617021 (-1425 2475);
PAINT AQUA (-1425 2475);
DISPLAY INVISIBLE (-1425 2475);
FORCEPROP 1 LASTPIN (-1475 2475) $PN 1
J 0
(-1465 2455);
DISPLAY 1.063830 (-1465 2455);
PAINT ORANGE (-1465 2455);
DISPLAY INVISIBLE (-1465 2455);
FORCEPROP 2 LAST ROOM VDDQ_DEF_PWR_VR
J 0
(-1425 2525);
DISPLAY 1.361702 (-1425 2525);
PAINT ORANGE (-1425 2525);
DISPLAY INVISIBLE (-1425 2525);
FORCEPROP 1 LAST PATH I51
J 0
(-1425 2525);
DISPLAY 0.978723 (-1425 2525);
PAINT WHITE (-1425 2525);
DISPLAY INVISIBLE (-1425 2525);
FORCEPROP 2 LAST CDS_SEC 1
J 0
(-1425 2600);
DISPLAY 1.021277 (-1425 2600);
PAINT ORANGE (-1425 2600);
DISPLAY INVISIBLE (-1425 2600);
FORCEPROP 2 LAST $SEC 1
J 0
(-1425 2600);
DISPLAY 0.680851 (-1425 2600);
PAINT MONO (-1425 2600);
DISPLAY INVISIBLE (-1425 2600);
FORCEADD RES..1
(-975 2950);
FORCEPROP 1 LAST VALUE 1.0
J 2
(-1075 2825);
DISPLAY 0.617021 (-1075 2825);
PAINT SKYBLUE (-1075 2825);
FORCEPROP 1 LAST WATTAGE 1/16W
J 2
(-950 2775);
DISPLAY 0.617021 (-950 2775);
PAINT SKYBLUE (-950 2775);
FORCEPROP 1 LAST TOLERANCE 1%
J 0
(-1025 2825);
DISPLAY 0.617021 (-1025 2825);
PAINT SKYBLUE (-1025 2825);
FORCEPROP 1 LAST PART_NUMBER G21796-090
J 0
(-1100 2875);
DISPLAY 0.617021 (-1100 2875);
PAINT BLUE (-1100 2875);
FORCEPROP 1 LAST LOCATION R3L6
J 0
(-1025 3000);
DISPLAY 0.617021 (-1025 3000);
PAINT AQUA (-1025 3000);
FORCEPROP 1 LAST PACK_TYPE 0402
J 0
(-925 2825);
DISPLAY 0.617021 (-925 2825);
PAINT SKYBLUE (-925 2825);
FORCEPROP 1 LAST MATERIAL CHIP
J 0
(-900 2775);
DISPLAY 0.617021 (-900 2775);
PAINT SKYBLUE (-900 2775);
FORCEPROP 1 LASTPIN (-1075 2950) $PN 1
J 0
(-1063 2962);
DISPLAY 1.063830 (-1063 2962);
PAINT ORANGE (-1063 2962);
DISPLAY INVISIBLE (-1063 2962);
FORCEPROP 2 LAST CDS_LOCATION R3L6
J 0
(-1025 3000);
DISPLAY 0.617021 (-1025 3000);
PAINT AQUA (-1025 3000);
DISPLAY INVISIBLE (-1025 3000);
FORCEPROP 2 LAST ROOM VDDQ_DEF_PWR_VR
J 0
(-1025 3050);
DISPLAY 1.361702 (-1025 3050);
PAINT ORANGE (-1025 3050);
DISPLAY INVISIBLE (-1025 3050);
FORCEPROP 1 LAST PATH I52
J 0
(-1025 3100);
DISPLAY 1.319149 (-1025 3100);
PAINT WHITE (-1025 3100);
DISPLAY INVISIBLE (-1025 3100);
FORCEPROP 2 LAST $SEC 1
J 0
(-1025 3175);
DISPLAY 0.680851 (-1025 3175);
PAINT MONO (-1025 3175);
DISPLAY INVISIBLE (-1025 3175);
FORCEPROP 2 LAST CDS_SEC 1
J 0
(-1025 3175);
DISPLAY 1.021277 (-1025 3175);
PAINT ORANGE (-1025 3175);
DISPLAY INVISIBLE (-1025 3175);
FORCEPROP 2 LAST CDS_LIB mstr_discrete
J 0
(-975 2950);
PAINT ORANGE (-975 2950);
DISPLAY INVISIBLE (-975 2950);
FORCEPROP 1 LASTPIN (-875 2950) $PN 2
J 0
(-913 2962);
DISPLAY 1.063830 (-913 2962);
PAINT ORANGE (-913 2962);
DISPLAY INVISIBLE (-913 2962);
FORCEADD CAP_A..1
R 2
(-575 2375);
FORCEPROP 1 LAST PACK_TYPE 0402V
J 2
(-625 2175);
DISPLAY 0.617021 (-625 2175);
PAINT SKYBLUE (-625 2175);
FORCEPROP 1 LAST VALUE 1.0UF
J 2
(-625 2425);
DISPLAY 0.617021 (-625 2425);
PAINT SKYBLUE (-625 2425);
FORCEPROP 1 LAST PART_NUMBER D97712-004
J 2
(-625 2225);
DISPLAY 0.617021 (-625 2225);
PAINT BLUE (-625 2225);
FORCEPROP 1 LAST LOCATION C7A18
J 2
(-625 2475);
DISPLAY 0.617021 (-625 2475);
PAINT AQUA (-625 2475);
FORCEPROP 1 LAST MATERIAL X6S
J 2
(-625 2275);
DISPLAY 0.617021 (-625 2275);
PAINT SKYBLUE (-625 2275);
FORCEPROP 1 LAST VOLTAGE 6.3V
J 2
(-625 2375);
DISPLAY 0.617021 (-625 2375);
PAINT SKYBLUE (-625 2375);
FORCEPROP 1 LAST TOLERANCE 10%
J 2
(-625 2325);
DISPLAY 0.617021 (-625 2325);
PAINT SKYBLUE (-625 2325);
FORCEPROP 1 LASTPIN (-575 2275) $PN 2
J 2
(-585 2255);
DISPLAY 1.063830 (-585 2255);
PAINT ORANGE (-585 2255);
DISPLAY INVISIBLE (-585 2255);
FORCEPROP 1 LASTPIN (-575 2475) $PN 1
J 2
(-585 2455);
DISPLAY 1.063830 (-585 2455);
PAINT ORANGE (-585 2455);
DISPLAY INVISIBLE (-585 2455);
FORCEPROP 2 LAST CDS_LIB dev_discrete
J 0
(-575 2375);
PAINT ORANGE (-575 2375);
DISPLAY INVISIBLE (-575 2375);
FORCEPROP 2 LAST CDS_LOCATION C7A18
J 2
(-625 2475);
DISPLAY 0.617021 (-625 2475);
PAINT AQUA (-625 2475);
DISPLAY INVISIBLE (-625 2475);
FORCEPROP 2 LAST ROOM VDDQ_DEF_PWR_VR
J 0
(-625 2525);
DISPLAY 1.361702 (-625 2525);
PAINT ORANGE (-625 2525);
DISPLAY INVISIBLE (-625 2525);
FORCEPROP 1 LAST PATH I53
J 2
(-625 2525);
DISPLAY 0.978723 (-625 2525);
PAINT WHITE (-625 2525);
DISPLAY INVISIBLE (-625 2525);
FORCEPROP 2 LAST CDS_SEC 1
J 0
(-625 2600);
DISPLAY 1.021277 (-625 2600);
PAINT ORANGE (-625 2600);
DISPLAY INVISIBLE (-625 2600);
FORCEPROP 2 LAST $SEC 1
J 0
(-625 2600);
DISPLAY 0.680851 (-625 2600);
PAINT MONO (-625 2600);
DISPLAY INVISIBLE (-625 2600);
FORCEADD CAP..1
(-475 2375);
FORCEPROP 1 LAST PACK_TYPE 0402
J 0
(-425 2175);
DISPLAY 0.617021 (-425 2175);
PAINT SKYBLUE (-425 2175);
FORCEPROP 1 LAST MATERIAL X7R
J 0
(-425 2275);
DISPLAY 0.617021 (-425 2275);
PAINT SKYBLUE (-425 2275);
FORCEPROP 1 LAST VOLTAGE 16V
J 0
(-425 2375);
DISPLAY 0.617021 (-425 2375);
PAINT SKYBLUE (-425 2375);
FORCEPROP 1 LAST LOCATION C7A17
J 0
(-425 2475);
DISPLAY 0.617021 (-425 2475);
PAINT AQUA (-425 2475);
FORCEPROP 1 LAST TOLERANCE 10%
J 0
(-425 2325);
DISPLAY 0.617021 (-425 2325);
PAINT SKYBLUE (-425 2325);
FORCEPROP 1 LAST PART_NUMBER A36096-155
J 0
(-425 2225);
DISPLAY 0.617021 (-425 2225);
PAINT BLUE (-425 2225);
FORCEPROP 1 LAST VALUE 0.22UF
J 0
(-425 2425);
DISPLAY 0.617021 (-425 2425);
PAINT SKYBLUE (-425 2425);
FORCEPROP 1 LASTPIN (-475 2275) $PN 2
J 0
(-465 2255);
DISPLAY 1.063830 (-465 2255);
PAINT ORANGE (-465 2255);
DISPLAY INVISIBLE (-465 2255);
FORCEPROP 1 LASTPIN (-475 2475) $PN 1
J 0
(-465 2455);
DISPLAY 1.063830 (-465 2455);
PAINT ORANGE (-465 2455);
DISPLAY INVISIBLE (-465 2455);
FORCEPROP 2 LAST CDS_LOCATION C7A17
J 0
(-425 2475);
DISPLAY 0.617021 (-425 2475);
PAINT AQUA (-425 2475);
DISPLAY INVISIBLE (-425 2475);
FORCEPROP 2 LAST CDS_LIB mstr_discrete
J 0
(-475 2375);
PAINT ORANGE (-475 2375);
DISPLAY INVISIBLE (-475 2375);
FORCEPROP 1 LAST PATH I54
J 0
(-425 2525);
DISPLAY 1.319149 (-425 2525);
PAINT WHITE (-425 2525);
DISPLAY INVISIBLE (-425 2525);
FORCEPROP 2 LAST ROOM VDDQ_DEF_PWR_VR
J 0
(-425 2525);
DISPLAY 1.361702 (-425 2525);
PAINT ORANGE (-425 2525);
DISPLAY INVISIBLE (-425 2525);
FORCEPROP 2 LAST CDS_SEC 1
J 0
(-425 2600);
DISPLAY 1.021277 (-425 2600);
PAINT ORANGE (-425 2600);
DISPLAY INVISIBLE (-425 2600);
FORCEPROP 2 LAST $SEC 1
J 0
(-425 2600);
DISPLAY 0.680851 (-425 2600);
PAINT MONO (-425 2600);
DISPLAY INVISIBLE (-425 2600);
FORCEADD INDUCTOR..1
(3400 1775);
FORCEPROP 1 LAST MATERIAL IND
J 0
(3440 1665);
DISPLAY 0.617021 (3440 1665);
PAINT SKYBLUE (3440 1665);
FORCEPROP 1 LAST LOCATION L7A1
J 0
(3300 1825);
DISPLAY 0.617021 (3300 1825);
PAINT AQUA (3300 1825);
FORCEPROP 1 LAST VALUE 0.12UH
J 2
(3270 1740);
DISPLAY 0.617021 (3270 1740);
PAINT SKYBLUE (3270 1740);
FORCEPROP 1 LAST PACK_TYPE SM
J 0
(3565 1665);
DISPLAY 0.617021 (3565 1665);
PAINT SKYBLUE (3565 1665);
FORCEPROP 1 LAST PART_NUMBER D92183-034
J 0
(3275 1725);
DISPLAY 0.617021 (3275 1725);
PAINT BLUE (3275 1725);
FORCEPROP 2 LAST CDS_LIB mstr_discrete
J 0
(3400 1775);
PAINT ORANGE (3400 1775);
DISPLAY INVISIBLE (3400 1775);
FORCEPROP 1 LASTPIN (3500 1775) $PN 2
J 2
(3510 1785);
DISPLAY 0.936170 (3510 1785);
PAINT WHITE (3510 1785);
DISPLAY INVISIBLE (3510 1785);
FORCEPROP 2 LAST CDS_SEC 1
J 0
(3300 2000);
DISPLAY 1.021277 (3300 2000);
PAINT ORANGE (3300 2000);
DISPLAY INVISIBLE (3300 2000);
FORCEPROP 2 LAST $SEC 1
J 0
(3300 2000);
DISPLAY 0.680851 (3300 2000);
PAINT MONO (3300 2000);
DISPLAY INVISIBLE (3300 2000);
FORCEPROP 2 LAST CDS_LOCATION L7A1
J 0
(3300 1825);
DISPLAY 0.617021 (3300 1825);
PAINT AQUA (3300 1825);
DISPLAY INVISIBLE (3300 1825);
FORCEPROP 1 LAST PATH I55
J 0
(3300 1925);
DISPLAY 1.319149 (3300 1925);
PAINT ORANGE (3300 1925);
DISPLAY INVISIBLE (3300 1925);
FORCEPROP 2 LAST ROOM VDDQ_DEF_PWR_VR
J 0
(3300 1875);
DISPLAY 1.361702 (3300 1875);
PAINT ORANGE (3300 1875);
DISPLAY INVISIBLE (3300 1875);
FORCEPROP 1 LASTPIN (3300 1775) $PN 1
J 0
(3300 1785);
DISPLAY 0.936170 (3300 1785);
PAINT WHITE (3300 1785);
DISPLAY INVISIBLE (3300 1785);
FORCEADD OFFPAGE..2
(3225 2250);
FORCEPROP 2 LAST $XR1 218 
J 0
(3534 2250);
DISPLAY 0.638298 (3534 2250);
PAINT MONO (3534 2250);
FORCEPROP 2 LAST $XR0 219 
J 0
(3414 2250);
DISPLAY 0.638298 (3414 2250);
PAINT MONO (3414 2250);
FORCEPROP 2 LAST BOM_COST PROC_VRD_VCCIN_CPU0
J 0
(3425 2300);
DISPLAY 1.446809 (3425 2300);
PAINT MONO (3425 2300);
DISPLAY INVISIBLE (3425 2300);
FORCEPROP 2 LAST PATH I58
J 0
(3405 2325);
DISPLAY 1.361702 (3405 2325);
PAINT ORANGE (3405 2325);
DISPLAY INVISIBLE (3405 2325);
FORCEPROP 2 LAST CDS_LIB mstr_standard
J 0
(3225 2250);
PAINT ORANGE (3225 2250);
DISPLAY INVISIBLE (3225 2250);
FORCEPROP 2 LAST ROOM VDDQ_DEF_PWR_VR
J 0
(2825 2325);
DISPLAY 1.936170 (2825 2325);
PAINT ORANGE (2825 2325);
DISPLAY INVISIBLE (2825 2325);
FORCEPROP 1 LAST OFFPAGE TRUE
J 0
(3550 2125);
DISPLAY 1.723404 (3550 2125);
PAINT GREEN (3550 2125);
DISPLAY INVISIBLE (3550 2125);
FORCEPROP 1 LAST COMMENT_BODY TRUE
J 0
(3180 2155);
DISPLAY 1.723404 (3180 2155);
PAINT GREEN (3180 2155);
DISPLAY INVISIBLE (3180 2155);
FORCEADD OFFPAGE..2
(3275 825);
FORCEPROP 2 LAST $XR0 218 
J 0
(3464 825);
DISPLAY 0.638298 (3464 825);
PAINT MONO (3464 825);
FORCEPROP 2 LAST ROOM VDDQ_DEF_PWR_VR
J 0
(2875 900);
DISPLAY 1.936170 (2875 900);
PAINT ORANGE (2875 900);
DISPLAY INVISIBLE (2875 900);
FORCEPROP 1 LAST COMMENT_BODY TRUE
J 0
(3230 730);
DISPLAY 1.723404 (3230 730);
PAINT GREEN (3230 730);
DISPLAY INVISIBLE (3230 730);
FORCEPROP 2 LAST CDS_LIB mstr_standard
J 0
(3275 825);
PAINT ORANGE (3275 825);
DISPLAY INVISIBLE (3275 825);
FORCEPROP 2 LAST PATH I61
J 0
(3455 900);
DISPLAY 1.361702 (3455 900);
PAINT ORANGE (3455 900);
DISPLAY INVISIBLE (3455 900);
FORCEPROP 2 LAST BOM_COST PROC_VRD_VCCIN_CPU0
J 0
(3475 875);
DISPLAY 1.446809 (3475 875);
PAINT MONO (3475 875);
DISPLAY INVISIBLE (3475 875);
FORCEPROP 1 LAST OFFPAGE TRUE
J 0
(3600 700);
DISPLAY 1.723404 (3600 700);
PAINT GREEN (3600 700);
DISPLAY INVISIBLE (3600 700);
FORCEADD OFFPAGE..2
(3350 500);
FORCEPROP 2 LAST $XR0 218 
J 0
(3539 500);
DISPLAY 0.638298 (3539 500);
PAINT MONO (3539 500);
FORCEPROP 2 LAST ROOM VDDQ_DEF_PWR_VR
J 0
(2950 575);
DISPLAY 1.936170 (2950 575);
PAINT ORANGE (2950 575);
DISPLAY INVISIBLE (2950 575);
FORCEPROP 1 LAST COMMENT_BODY TRUE
J 0
(3305 405);
DISPLAY 1.723404 (3305 405);
PAINT GREEN (3305 405);
DISPLAY INVISIBLE (3305 405);
FORCEPROP 2 LAST CDS_LIB mstr_standard
J 0
(3350 500);
PAINT ORANGE (3350 500);
DISPLAY INVISIBLE (3350 500);
FORCEPROP 2 LAST PATH I62
J 0
(3530 575);
DISPLAY 1.361702 (3530 575);
PAINT ORANGE (3530 575);
DISPLAY INVISIBLE (3530 575);
FORCEPROP 2 LAST BOM_COST PROC_VRD_VCCIN_CPU0
J 0
(3550 550);
DISPLAY 1.446809 (3550 550);
PAINT MONO (3550 550);
DISPLAY INVISIBLE (3550 550);
FORCEPROP 1 LAST OFFPAGE TRUE
J 0
(3675 375);
DISPLAY 1.723404 (3675 375);
PAINT GREEN (3675 375);
DISPLAY INVISIBLE (3675 375);
FORCEADD OFFPAGE..2
(3525 150);
FORCEPROP 2 LAST $XR1 218 
J 0
(3834 150);
DISPLAY 0.638298 (3834 150);
PAINT MONO (3834 150);
FORCEPROP 2 LAST $XR0 219 
J 0
(3714 150);
DISPLAY 0.638298 (3714 150);
PAINT MONO (3714 150);
FORCEPROP 2 LAST BOM_COST PROC_VRD_VCCIN_CPU0
J 0
(3725 200);
DISPLAY 1.446809 (3725 200);
PAINT MONO (3725 200);
DISPLAY INVISIBLE (3725 200);
FORCEPROP 2 LAST PATH I63
J 0
(3705 225);
DISPLAY 1.361702 (3705 225);
PAINT ORANGE (3705 225);
DISPLAY INVISIBLE (3705 225);
FORCEPROP 2 LAST ROOM VDDQ_DEF_PWR_VR
J 0
(3125 225);
DISPLAY 1.936170 (3125 225);
PAINT ORANGE (3125 225);
DISPLAY INVISIBLE (3125 225);
FORCEPROP 2 LAST CDS_LIB mstr_standard
J 0
(3525 150);
PAINT ORANGE (3525 150);
DISPLAY INVISIBLE (3525 150);
FORCEPROP 1 LAST OFFPAGE TRUE
J 0
(3850 25);
DISPLAY 1.723404 (3850 25);
PAINT GREEN (3850 25);
DISPLAY INVISIBLE (3850 25);
FORCEPROP 1 LAST COMMENT_BODY TRUE
J 0
(3480 55);
DISPLAY 1.723404 (3480 55);
PAINT GREEN (3480 55);
DISPLAY INVISIBLE (3480 55);
FORCEADD PVDDQ_DEF..1
(4100 -250);
FORCEPROP 3 LASTPIN (4100 -300) SIG_NAME PVDDQ_DEF\g
J 0
(4110 -290);
DISPLAY 0.659574 (4110 -290);
PAINT MONO (4110 -290);
DISPLAY INVISIBLE (4110 -290);
FORCEPROP 1 LAST BODY_TYPE PLUMBING
J 0
(4055 -293);
DISPLAY 0.340426 (4055 -293);
PAINT GREEN (4055 -293);
DISPLAY INVISIBLE (4055 -293);
FORCEPROP 1 LAST VOLTAGE 1.2V
J 0
(4055 -293);
DISPLAY 0.340426 (4055 -293);
PAINT SKYBLUE (4055 -293);
DISPLAY INVISIBLE (4055 -293);
FORCEPROP 1 LAST HDL_POWER PVDDQ_DEF
J 1
(4100 -200);
DISPLAY 0.872340 (4100 -200);
PAINT GREEN (4100 -200);
DISPLAY INVISIBLE (4100 -200);
FORCEPROP 2 LAST ROOM VDDQ_DEF_PWR_VR
J 0
(4100 -150);
DISPLAY 1.936170 (4100 -150);
PAINT ORANGE (4100 -150);
DISPLAY INVISIBLE (4100 -150);
FORCEPROP 1 LAST PATH I64
J 0
(4150 -225);
DISPLAY 0.872340 (4150 -225);
PAINT AQUA (4150 -225);
DISPLAY INVISIBLE (4150 -225);
FORCEPROP 2 LAST CDS_LIB mstr_symbols
J 0
(4100 -250);
PAINT ORANGE (4100 -250);
DISPLAY INVISIBLE (4100 -250);
FORCEPROP 2 LAST BOM_COST PROC_SOCKET 
J 0
(4100 -150);
DISPLAY 1.446809 (4100 -150);
PAINT MONO (4100 -150);
DISPLAY INVISIBLE (4100 -150);
FORCEADD INDUCTOR..1
(3175 -350);
FORCEPROP 1 LASTPIN (3075 -350) $PN 1
J 0
(3075 -340);
DISPLAY 0.617021 (3075 -340);
PAINT WHITE (3075 -340);
FORCEPROP 1 LAST PACK_TYPE SM
J 0
(3340 -460);
DISPLAY 0.617021 (3340 -460);
PAINT SKYBLUE (3340 -460);
FORCEPROP 1 LAST PART_NUMBER D92183-034
J 0
(3050 -400);
DISPLAY 0.617021 (3050 -400);
PAINT BLUE (3050 -400);
FORCEPROP 1 LASTPIN (3275 -350) $PN 2
J 2
(3285 -340);
DISPLAY 0.617021 (3285 -340);
PAINT WHITE (3285 -340);
FORCEPROP 1 LAST MATERIAL IND
J 0
(3215 -460);
DISPLAY 0.617021 (3215 -460);
PAINT SKYBLUE (3215 -460);
FORCEPROP 1 LAST LOCATION L7A3
J 0
(3075 -300);
DISPLAY 0.617021 (3075 -300);
PAINT AQUA (3075 -300);
FORCEPROP 1 LAST VALUE 0.12UH
J 2
(3170 -460);
DISPLAY 0.617021 (3170 -460);
PAINT SKYBLUE (3170 -460);
FORCEPROP 2 LAST CDS_LOCATION L7A3
J 0
(3075 -300);
DISPLAY 0.617021 (3075 -300);
PAINT AQUA (3075 -300);
DISPLAY INVISIBLE (3075 -300);
FORCEPROP 2 LAST CDS_LIB mstr_discrete
J 0
(3175 -350);
PAINT ORANGE (3175 -350);
DISPLAY INVISIBLE (3175 -350);
FORCEPROP 2 LAST ROOM VDDQ_DEF_PWR_VR
J 0
(3075 -250);
DISPLAY 1.361702 (3075 -250);
PAINT ORANGE (3075 -250);
DISPLAY INVISIBLE (3075 -250);
FORCEPROP 1 LAST PATH I65
J 0
(3075 -200);
DISPLAY 1.319149 (3075 -200);
PAINT ORANGE (3075 -200);
DISPLAY INVISIBLE (3075 -200);
FORCEPROP 2 LAST SEC 1
J 0
(3075 -125);
DISPLAY 0.680851 (3075 -125);
PAINT MONO (3075 -125);
DISPLAY INVISIBLE (3075 -125);
FORCEPROP 2 LAST SEC_TYPE SM
J 0
(3075 -125);
DISPLAY 1.021277 (3075 -125);
PAINT ORANGE (3075 -125);
DISPLAY INVISIBLE (3075 -125);
FORCEADD CAP..1
(4100 -550);
FORCEPROP 1 LASTPIN (4100 -650) $PN 2
J 0
(4110 -670);
DISPLAY 0.617021 (4110 -670);
PAINT ORANGE (4110 -670);
FORCEPROP 1 LAST MATERIAL X6S
J 0
(4150 -650);
DISPLAY 0.617021 (4150 -650);
PAINT SKYBLUE (4150 -650);
FORCEPROP 1 LAST PACK_TYPE 0805LF
J 0
(4150 -750);
DISPLAY 0.617021 (4150 -750);
PAINT SKYBLUE (4150 -750);
FORCEPROP 1 LAST TOLERANCE 20%
J 0
(4150 -600);
DISPLAY 0.617021 (4150 -600);
PAINT SKYBLUE (4150 -600);
FORCEPROP 1 LAST PART_NUMBER C95333-002
J 0
(4150 -700);
DISPLAY 0.617021 (4150 -700);
PAINT BLUE (4150 -700);
FORCEPROP 1 LASTPIN (4100 -450) $PN 1
J 0
(4110 -470);
DISPLAY 0.617021 (4110 -470);
PAINT ORANGE (4110 -470);
FORCEPROP 1 LAST VALUE 22UF
J 0
(4150 -500);
DISPLAY 0.617021 (4150 -500);
PAINT SKYBLUE (4150 -500);
FORCEPROP 1 LAST LOCATION C6A4
J 0
(4150 -450);
DISPLAY 0.617021 (4150 -450);
PAINT AQUA (4150 -450);
FORCEPROP 2 LAST CDS_LIB mstr_discrete
J 0
(4100 -550);
PAINT ORANGE (4100 -550);
DISPLAY INVISIBLE (4100 -550);
FORCEPROP 1 LAST VOLTAGE 4V
J 0
(4150 -550);
DISPLAY 1.446809 (4150 -550);
PAINT SKYBLUE (4150 -550);
DISPLAY INVISIBLE (4150 -550);
FORCEPROP 2 LAST CDS_LOCATION C6A4
J 0
(4150 -450);
DISPLAY 0.617021 (4150 -450);
PAINT AQUA (4150 -450);
DISPLAY INVISIBLE (4150 -450);
FORCEPROP 2 LAST ROOM VDDQ_DEF_PWR_VR
J 0
(4150 -400);
DISPLAY 1.446809 (4150 -400);
PAINT MONO (4150 -400);
DISPLAY INVISIBLE (4150 -400);
FORCEPROP 1 LAST PATH I68
J 0
(4150 -400);
DISPLAY 1.319149 (4150 -400);
PAINT WHITE (4150 -400);
DISPLAY INVISIBLE (4150 -400);
FORCEPROP 2 LAST BOM_COST PROC_VRD_VCCIN_CPU0
J 0
(4150 -400);
DISPLAY 1.446809 (4150 -400);
PAINT MONO (4150 -400);
DISPLAY INVISIBLE (4150 -400);
FORCEPROP 2 LAST SEC 1
J 0
(4155 -325);
DISPLAY 0.680851 (4155 -325);
PAINT MONO (4155 -325);
DISPLAY INVISIBLE (4155 -325);
FORCEPROP 2 LAST SEC_TYPE 0805LF
J 0
(4155 -325);
DISPLAY 1.021277 (4155 -325);
PAINT ORANGE (4155 -325);
DISPLAY INVISIBLE (4155 -325);
FORCEADD GND..1
(4100 -775);
FORCEPROP 3 LASTPIN (4100 -725) SIG_NAME GND\g
J 0
(4110 -715);
DISPLAY 0.659574 (4110 -715);
PAINT MONO (4110 -715);
DISPLAY INVISIBLE (4110 -715);
FORCEPROP 2 LAST ROOM VDDQ_DEF_PWR_VR
J 0
(3550 -700);
DISPLAY 1.936170 (3550 -700);
PAINT ORANGE (3550 -700);
DISPLAY INVISIBLE (3550 -700);
FORCEPROP 1 LAST BODY_TYPE PLUMBING
J 0
(4055 -818);
DISPLAY 0.340426 (4055 -818);
PAINT GREEN (4055 -818);
DISPLAY INVISIBLE (4055 -818);
FORCEPROP 2 LAST BOM_COST PROC_VRD_VCCIN_CPU0
J 0
(3725 -700);
DISPLAY 1.446809 (3725 -700);
PAINT MONO (3725 -700);
DISPLAY INVISIBLE (3725 -700);
FORCEPROP 1 LAST PATH I69
J 0
(4175 -775);
DISPLAY 1.170213 (4175 -775);
PAINT AQUA (4175 -775);
DISPLAY INVISIBLE (4175 -775);
FORCEPROP 1 LAST SIZE 1B
J 0
(4175 -825);
DISPLAY 1.723404 (4175 -825);
PAINT GREEN (4175 -825);
DISPLAY INVISIBLE (4175 -825);
FORCEPROP 2 LAST CDS_LIB mstr_symbols
J 0
(4100 -775);
PAINT ORANGE (4100 -775);
DISPLAY INVISIBLE (4100 -775);
FORCEPROP 1 LAST VOLTAGE 0
J 0
(4100 -775);
PAINT SKYBLUE (4100 -775);
DISPLAY INVISIBLE (4100 -775);
FORCEPROP 1 LAST HDL_POWER GND
J 0
(4100 -625);
DISPLAY 1.723404 (4100 -625);
PAINT GREEN (4100 -625);
DISPLAY INVISIBLE (4100 -625);
FORCEADD GND..1
(4075 1350);
FORCEPROP 3 LASTPIN (4075 1400) SIG_NAME GND\g
J 0
(4085 1410);
DISPLAY 0.659574 (4085 1410);
PAINT MONO (4085 1410);
DISPLAY INVISIBLE (4085 1410);
FORCEPROP 2 LAST ROOM VDDQ_DEF_PWR_VR
J 0
(3525 1425);
DISPLAY 1.936170 (3525 1425);
PAINT ORANGE (3525 1425);
DISPLAY INVISIBLE (3525 1425);
FORCEPROP 2 LAST BOM_COST PROC_VRD_VCCIN_CPU0
J 0
(3700 1425);
DISPLAY 1.446809 (3700 1425);
PAINT MONO (3700 1425);
DISPLAY INVISIBLE (3700 1425);
FORCEPROP 1 LAST VOLTAGE 0
J 0
(4075 1350);
PAINT SKYBLUE (4075 1350);
DISPLAY INVISIBLE (4075 1350);
FORCEPROP 2 LAST CDS_LIB mstr_symbols
J 0
(4075 1350);
DISPLAY 1.936170 (4075 1350);
PAINT ORANGE (4075 1350);
DISPLAY INVISIBLE (4075 1350);
FORCEPROP 1 LAST BODY_TYPE PLUMBING
J 0
(4030 1307);
DISPLAY 0.340426 (4030 1307);
PAINT GREEN (4030 1307);
DISPLAY INVISIBLE (4030 1307);
FORCEPROP 1 LAST HDL_POWER GND
J 0
(4075 1500);
DISPLAY 1.723404 (4075 1500);
PAINT GREEN (4075 1500);
DISPLAY INVISIBLE (4075 1500);
FORCEPROP 1 LAST PATH I7
J 0
(4150 1350);
DISPLAY 0.893617 (4150 1350);
PAINT AQUA (4150 1350);
DISPLAY INVISIBLE (4150 1350);
FORCEPROP 1 LAST SIZE 1B
J 0
(4150 1300);
DISPLAY 1.723404 (4150 1300);
PAINT GREEN (4150 1300);
DISPLAY INVISIBLE (4150 1300);
FORCEADD GND..1
(2425 -800);
FORCEPROP 3 LASTPIN (2425 -750) SIG_NAME GND\g
J 0
(2435 -740);
DISPLAY 0.659574 (2435 -740);
PAINT MONO (2435 -740);
DISPLAY INVISIBLE (2435 -740);
FORCEPROP 2 LAST ROOM VDDQ_DEF_PWR_VR
J 0
(1875 -725);
DISPLAY 1.936170 (1875 -725);
PAINT ORANGE (1875 -725);
DISPLAY INVISIBLE (1875 -725);
FORCEPROP 2 LAST BOM_COST PROC_VRD_VCCIN_CPU0
J 0
(2050 -725);
DISPLAY 1.446809 (2050 -725);
PAINT MONO (2050 -725);
DISPLAY INVISIBLE (2050 -725);
FORCEPROP 1 LAST BODY_TYPE PLUMBING
J 0
(2380 -843);
DISPLAY 0.340426 (2380 -843);
PAINT GREEN (2380 -843);
DISPLAY INVISIBLE (2380 -843);
FORCEPROP 1 LAST SIZE 1B
J 0
(2500 -850);
DISPLAY 1.723404 (2500 -850);
PAINT GREEN (2500 -850);
DISPLAY INVISIBLE (2500 -850);
FORCEPROP 1 LAST PATH I70
J 0
(2500 -800);
DISPLAY 1.170213 (2500 -800);
PAINT AQUA (2500 -800);
DISPLAY INVISIBLE (2500 -800);
FORCEPROP 1 LAST VOLTAGE 0
J 0
(2425 -800);
PAINT SKYBLUE (2425 -800);
DISPLAY INVISIBLE (2425 -800);
FORCEPROP 2 LAST CDS_LIB mstr_symbols
J 0
(2425 -800);
PAINT ORANGE (2425 -800);
DISPLAY INVISIBLE (2425 -800);
FORCEPROP 1 LAST HDL_POWER GND
J 0
(2425 -650);
DISPLAY 1.723404 (2425 -650);
PAINT GREEN (2425 -650);
DISPLAY INVISIBLE (2425 -650);
FORCEADD CAP..1
(-550 250);
FORCEPROP 1 LASTPIN (-550 350) $PN 1
J 0
(-540 330);
DISPLAY 0.617021 (-540 330);
PAINT ORANGE (-540 330);
FORCEPROP 1 LASTPIN (-550 150) $PN 2
J 0
(-540 130);
DISPLAY 0.617021 (-540 130);
PAINT ORANGE (-540 130);
FORCEPROP 1 LAST MATERIAL X7R
J 0
(-500 150);
DISPLAY 0.617021 (-500 150);
PAINT SKYBLUE (-500 150);
FORCEPROP 1 LAST VOLTAGE 16V
J 0
(-500 250);
DISPLAY 0.617021 (-500 250);
PAINT SKYBLUE (-500 250);
FORCEPROP 1 LAST PACK_TYPE 0402
J 0
(-500 50);
DISPLAY 0.617021 (-500 50);
PAINT SKYBLUE (-500 50);
FORCEPROP 1 LAST TOLERANCE 10%
J 0
(-500 200);
DISPLAY 0.617021 (-500 200);
PAINT SKYBLUE (-500 200);
FORCEPROP 1 LAST VALUE 0.22UF
J 0
(-500 300);
DISPLAY 0.617021 (-500 300);
PAINT SKYBLUE (-500 300);
FORCEPROP 1 LAST LOCATION C7A25
J 0
(-500 350);
DISPLAY 0.617021 (-500 350);
PAINT AQUA (-500 350);
FORCEPROP 1 LAST PART_NUMBER A36096-155
J 0
(-500 100);
DISPLAY 0.617021 (-500 100);
PAINT BLUE (-500 100);
FORCEPROP 2 LAST CDS_LIB mstr_discrete
J 0
(-550 250);
PAINT ORANGE (-550 250);
DISPLAY INVISIBLE (-550 250);
FORCEPROP 2 LAST ROOM VDDQ_DEF_PWR_VR
J 0
(-500 400);
DISPLAY 1.361702 (-500 400);
PAINT ORANGE (-500 400);
DISPLAY INVISIBLE (-500 400);
FORCEPROP 1 LAST PATH I72
J 0
(-500 400);
DISPLAY 1.319149 (-500 400);
PAINT WHITE (-500 400);
DISPLAY INVISIBLE (-500 400);
FORCEPROP 2 LAST CDS_LOCATION C7A25
J 0
(-500 350);
DISPLAY 0.617021 (-500 350);
PAINT AQUA (-500 350);
DISPLAY INVISIBLE (-500 350);
FORCEPROP 2 LAST SEC 1
J 0
(-500 475);
DISPLAY 0.680851 (-500 475);
PAINT MONO (-500 475);
DISPLAY INVISIBLE (-500 475);
FORCEPROP 2 LAST SEC_TYPE 0402
J 0
(-500 475);
DISPLAY 1.021277 (-500 475);
PAINT ORANGE (-500 475);
DISPLAY INVISIBLE (-500 475);
FORCEADD CAP_A..1
R 2
(-725 250);
FORCEPROP 1 LAST PART_NUMBER D97712-004
J 2
(-775 100);
DISPLAY 0.617021 (-775 100);
PAINT BLUE (-775 100);
FORCEPROP 1 LAST MATERIAL X6S
J 2
(-775 150);
DISPLAY 0.617021 (-775 150);
PAINT SKYBLUE (-775 150);
FORCEPROP 1 LAST VOLTAGE 6.3V
J 2
(-775 250);
DISPLAY 0.617021 (-775 250);
PAINT SKYBLUE (-775 250);
FORCEPROP 1 LAST PACK_TYPE 0402V
J 2
(-775 50);
DISPLAY 0.617021 (-775 50);
PAINT SKYBLUE (-775 50);
FORCEPROP 1 LAST TOLERANCE 10%
J 2
(-775 200);
DISPLAY 0.617021 (-775 200);
PAINT SKYBLUE (-775 200);
FORCEPROP 1 LAST VALUE 1.0UF
J 2
(-775 300);
DISPLAY 0.617021 (-775 300);
PAINT SKYBLUE (-775 300);
FORCEPROP 1 LAST LOCATION C7A26
J 2
(-775 350);
DISPLAY 0.617021 (-775 350);
PAINT AQUA (-775 350);
FORCEPROP 1 LASTPIN (-725 150) $PN 2
J 2
(-735 130);
DISPLAY 0.617021 (-735 130);
PAINT ORANGE (-735 130);
FORCEPROP 1 LASTPIN (-725 350) $PN 1
J 2
(-735 330);
DISPLAY 0.617021 (-735 330);
PAINT ORANGE (-735 330);
FORCEPROP 2 LAST ROOM VDDQ_DEF_PWR_VR
J 0
(-775 400);
DISPLAY 1.361702 (-775 400);
PAINT ORANGE (-775 400);
DISPLAY INVISIBLE (-775 400);
FORCEPROP 1 LAST PATH I73
J 2
(-775 400);
DISPLAY 0.978723 (-775 400);
PAINT WHITE (-775 400);
DISPLAY INVISIBLE (-775 400);
FORCEPROP 2 LAST SEC 1
J 0
(-775 475);
DISPLAY 0.680851 (-775 475);
PAINT MONO (-775 475);
DISPLAY INVISIBLE (-775 475);
FORCEPROP 2 LAST CDS_LOCATION C7A26
J 2
(-775 350);
DISPLAY 0.617021 (-775 350);
PAINT AQUA (-775 350);
DISPLAY INVISIBLE (-775 350);
FORCEPROP 2 LAST CDS_SEC 1
J 0
(-775 400);
PAINT ORANGE (-775 400);
DISPLAY INVISIBLE (-775 400);
FORCEPROP 2 LAST CDS_LIB dev_discrete
J 0
(-725 250);
PAINT ORANGE (-725 250);
DISPLAY INVISIBLE (-725 250);
FORCEPROP 2 LAST SEC_TYPE 0402V
J 0
(-775 475);
DISPLAY 1.021277 (-775 475);
PAINT ORANGE (-775 475);
DISPLAY INVISIBLE (-775 475);
FORCEADD CAP..1
R 2
(-1000 -450);
FORCEPROP 1 LAST MATERIAL X7R
J 2
(-1050 -550);
DISPLAY 0.617021 (-1050 -550);
PAINT SKYBLUE (-1050 -550);
FORCEPROP 1 LAST VOLTAGE 16V
J 2
(-1050 -450);
DISPLAY 0.617021 (-1050 -450);
PAINT SKYBLUE (-1050 -450);
FORCEPROP 1 LAST PACK_TYPE 0402
J 2
(-1050 -650);
DISPLAY 0.617021 (-1050 -650);
PAINT SKYBLUE (-1050 -650);
FORCEPROP 1 LAST TOLERANCE 10%
J 2
(-1050 -500);
DISPLAY 0.617021 (-1050 -500);
PAINT SKYBLUE (-1050 -500);
FORCEPROP 1 LAST PART_NUMBER A36096-104
J 2
(-1050 -600);
DISPLAY 0.617021 (-1050 -600);
PAINT BLUE (-1050 -600);
FORCEPROP 1 LAST LOCATION C7A22
J 2
(-1050 -350);
DISPLAY 0.617021 (-1050 -350);
PAINT AQUA (-1050 -350);
FORCEPROP 1 LAST VALUE 0.220UF
J 2
(-1050 -400);
DISPLAY 0.617021 (-1050 -400);
PAINT SKYBLUE (-1050 -400);
FORCEPROP 2 LAST ROOM VDDQ_DEF_PWR_VR
J 0
(-1050 -300);
DISPLAY 1.361702 (-1050 -300);
PAINT ORANGE (-1050 -300);
DISPLAY INVISIBLE (-1050 -300);
FORCEPROP 1 LAST PATH I75
J 2
(-1050 -300);
DISPLAY 0.978723 (-1050 -300);
PAINT WHITE (-1050 -300);
DISPLAY INVISIBLE (-1050 -300);
FORCEPROP 2 LAST CDS_LOCATION C7A22
J 2
(-1050 -350);
DISPLAY 0.617021 (-1050 -350);
PAINT AQUA (-1050 -350);
DISPLAY INVISIBLE (-1050 -350);
FORCEPROP 2 LAST $SEC 1
J 0
(-1050 -250);
PAINT MONO (-1050 -250);
DISPLAY INVISIBLE (-1050 -250);
FORCEPROP 2 LAST CDS_SEC 1
J 0
(-1050 -250);
PAINT MONO (-1050 -250);
DISPLAY INVISIBLE (-1050 -250);
FORCEPROP 0 LAST SPOF TRUE
J 0
(-1050 -250);
DISPLAY 1.021277 (-1050 -250);
PAINT ORANGE (-1050 -250);
DISPLAY INVISIBLE (-1050 -250);
FORCEPROP 1 LASTPIN (-1000 -550) $PN 2
J 2
(-1010 -570);
DISPLAY 0.617021 (-1010 -570);
PAINT ORANGE (-1010 -570);
DISPLAY INVISIBLE (-1010 -570);
FORCEPROP 2 LAST CDS_LIB mstr_discrete
J 0
(-1000 -450);
PAINT ORANGE (-1000 -450);
DISPLAY INVISIBLE (-1000 -450);
FORCEPROP 1 LASTPIN (-1000 -350) $PN 1
J 2
(-1010 -370);
DISPLAY 0.617021 (-1010 -370);
PAINT ORANGE (-1010 -370);
DISPLAY INVISIBLE (-1010 -370);
FORCEADD RES..1
(-1100 775);
FORCEPROP 1 LAST VALUE 1.0
J 2
(-1200 650);
DISPLAY 0.617021 (-1200 650);
PAINT SKYBLUE (-1200 650);
FORCEPROP 1 LAST WATTAGE 1/16W
J 2
(-1075 600);
DISPLAY 0.617021 (-1075 600);
PAINT SKYBLUE (-1075 600);
FORCEPROP 1 LAST TOLERANCE 1%
J 0
(-1150 650);
DISPLAY 0.617021 (-1150 650);
PAINT SKYBLUE (-1150 650);
FORCEPROP 1 LASTPIN (-1200 775) $PN 1
J 0
(-1188 787);
DISPLAY 0.617021 (-1188 787);
PAINT ORANGE (-1188 787);
FORCEPROP 1 LAST LOCATION R3L8
J 0
(-1150 825);
DISPLAY 0.617021 (-1150 825);
PAINT AQUA (-1150 825);
FORCEPROP 1 LASTPIN (-1000 775) $PN 2
J 0
(-1038 787);
DISPLAY 0.617021 (-1038 787);
PAINT ORANGE (-1038 787);
FORCEPROP 1 LAST MATERIAL CHIP
J 0
(-1025 600);
DISPLAY 0.617021 (-1025 600);
PAINT SKYBLUE (-1025 600);
FORCEPROP 1 LAST PACK_TYPE 0402
J 0
(-1050 650);
DISPLAY 0.617021 (-1050 650);
PAINT SKYBLUE (-1050 650);
FORCEPROP 1 LAST PART_NUMBER G21796-090
J 0
(-1225 700);
DISPLAY 0.617021 (-1225 700);
PAINT BLUE (-1225 700);
FORCEPROP 2 LAST ROOM VDDQ_DEF_PWR_VR
J 0
(-1150 875);
DISPLAY 1.361702 (-1150 875);
PAINT ORANGE (-1150 875);
DISPLAY INVISIBLE (-1150 875);
FORCEPROP 1 LAST PATH I76
J 0
(-1150 925);
DISPLAY 1.319149 (-1150 925);
PAINT WHITE (-1150 925);
DISPLAY INVISIBLE (-1150 925);
FORCEPROP 2 LAST CDS_LOCATION R3L8
J 0
(-1150 825);
DISPLAY 0.617021 (-1150 825);
PAINT AQUA (-1150 825);
DISPLAY INVISIBLE (-1150 825);
FORCEPROP 2 LAST CDS_LIB mstr_discrete
J 0
(-1100 775);
PAINT ORANGE (-1100 775);
DISPLAY INVISIBLE (-1100 775);
FORCEPROP 2 LAST SEC 1
J 0
(-1150 1000);
DISPLAY 0.680851 (-1150 1000);
PAINT MONO (-1150 1000);
DISPLAY INVISIBLE (-1150 1000);
FORCEPROP 2 LAST SEC_TYPE 0402
J 0
(-1150 1000);
DISPLAY 1.021277 (-1150 1000);
PAINT ORANGE (-1150 1000);
DISPLAY INVISIBLE (-1150 1000);
FORCEADD CAP..1
(-1400 150);
FORCEPROP 1 LAST PACK_TYPE 0402
J 0
(-1350 -50);
DISPLAY 0.617021 (-1350 -50);
PAINT SKYBLUE (-1350 -50);
FORCEPROP 1 LAST PART_NUMBER D97712-011
J 0
(-1350 0);
DISPLAY 0.617021 (-1350 0);
PAINT BLUE (-1350 0);
FORCEPROP 1 LASTPIN (-1400 50) $PN 2
J 0
(-1390 30);
DISPLAY 0.617021 (-1390 30);
PAINT ORANGE (-1390 30);
FORCEPROP 1 LASTPIN (-1400 250) $PN 1
J 0
(-1390 230);
DISPLAY 0.617021 (-1390 230);
PAINT ORANGE (-1390 230);
FORCEPROP 1 LAST MATERIAL X6S
J 0
(-1350 50);
DISPLAY 0.617021 (-1350 50);
PAINT SKYBLUE (-1350 50);
FORCEPROP 1 LAST VOLTAGE 16V
J 0
(-1350 150);
DISPLAY 0.617021 (-1350 150);
PAINT SKYBLUE (-1350 150);
FORCEPROP 1 LAST LOCATION C7A24
J 0
(-1350 250);
DISPLAY 0.617021 (-1350 250);
PAINT AQUA (-1350 250);
FORCEPROP 1 LAST VALUE 1.0UF
J 0
(-1350 200);
DISPLAY 0.617021 (-1350 200);
PAINT SKYBLUE (-1350 200);
FORCEPROP 1 LAST TOLERANCE 10%
J 0
(-1350 100);
DISPLAY 0.617021 (-1350 100);
PAINT SKYBLUE (-1350 100);
FORCEPROP 2 LAST CDS_LIB mstr_discrete
J 0
(-1400 150);
PAINT ORANGE (-1400 150);
DISPLAY INVISIBLE (-1400 150);
FORCEPROP 2 LAST CDS_LOCATION C7A24
J 0
(-1350 250);
DISPLAY 0.617021 (-1350 250);
PAINT AQUA (-1350 250);
DISPLAY INVISIBLE (-1350 250);
FORCEPROP 2 LAST ROOM VDDQ_DEF_PWR_VR
J 0
(-1350 300);
DISPLAY 1.361702 (-1350 300);
PAINT ORANGE (-1350 300);
DISPLAY INVISIBLE (-1350 300);
FORCEPROP 1 LAST PATH I77
J 0
(-1350 300);
DISPLAY 1.319149 (-1350 300);
PAINT WHITE (-1350 300);
DISPLAY INVISIBLE (-1350 300);
FORCEPROP 2 LAST SEC 1
J 0
(-1350 375);
DISPLAY 0.680851 (-1350 375);
PAINT MONO (-1350 375);
DISPLAY INVISIBLE (-1350 375);
FORCEPROP 2 LAST SEC_TYPE 0402
J 0
(-1350 375);
DISPLAY 1.021277 (-1350 375);
PAINT ORANGE (-1350 375);
DISPLAY INVISIBLE (-1350 375);
FORCEADD CAP_A..1
(-1675 125);
FORCEPROP 1 LAST PACK_TYPE 0402V
J 0
(-1625 -75);
DISPLAY 0.617021 (-1625 -75);
PAINT SKYBLUE (-1625 -75);
FORCEPROP 1 LAST PART_NUMBER A36096-030
J 0
(-1625 -25);
DISPLAY 0.617021 (-1625 -25);
PAINT BLUE (-1625 -25);
FORCEPROP 1 LASTPIN (-1675 25) $PN 2
J 0
(-1665 5);
DISPLAY 0.617021 (-1665 5);
PAINT ORANGE (-1665 5);
FORCEPROP 1 LASTPIN (-1675 225) $PN 1
J 0
(-1665 205);
DISPLAY 0.617021 (-1665 205);
PAINT ORANGE (-1665 205);
FORCEPROP 1 LAST MATERIAL X7R
J 0
(-1625 25);
DISPLAY 0.617021 (-1625 25);
PAINT SKYBLUE (-1625 25);
FORCEPROP 1 LAST TOLERANCE 10%
J 0
(-1625 75);
DISPLAY 0.617021 (-1625 75);
PAINT SKYBLUE (-1625 75);
FORCEPROP 1 LAST VOLTAGE 16V
J 0
(-1625 125);
DISPLAY 0.617021 (-1625 125);
PAINT SKYBLUE (-1625 125);
FORCEPROP 1 LAST VALUE 0.1UF
J 0
(-1625 175);
DISPLAY 0.617021 (-1625 175);
PAINT SKYBLUE (-1625 175);
FORCEPROP 1 LAST LOCATION C7A20
J 0
(-1625 225);
DISPLAY 0.617021 (-1625 225);
PAINT AQUA (-1625 225);
FORCEPROP 2 LAST CDS_LOCATION C7A20
J 0
(-1625 225);
DISPLAY 0.617021 (-1625 225);
PAINT AQUA (-1625 225);
DISPLAY INVISIBLE (-1625 225);
FORCEPROP 2 LAST CDS_LIB dev_discrete
J 0
(-1675 125);
PAINT ORANGE (-1675 125);
DISPLAY INVISIBLE (-1675 125);
FORCEPROP 1 LAST PATH I78
J 0
(-1625 275);
DISPLAY 0.978723 (-1625 275);
PAINT WHITE (-1625 275);
DISPLAY INVISIBLE (-1625 275);
FORCEPROP 2 LAST ROOM VDDQ_DEF_PWR_VR
J 0
(-1625 275);
DISPLAY 1.361702 (-1625 275);
PAINT ORANGE (-1625 275);
DISPLAY INVISIBLE (-1625 275);
FORCEPROP 2 LAST CDS_SEC 1
J 0
(-1625 275);
PAINT ORANGE (-1625 275);
DISPLAY INVISIBLE (-1625 275);
FORCEPROP 2 LAST SEC_TYPE 0402V
J 0
(-1625 350);
DISPLAY 1.021277 (-1625 350);
PAINT ORANGE (-1625 350);
DISPLAY INVISIBLE (-1625 350);
FORCEPROP 2 LAST SEC 1
J 0
(-1625 350);
DISPLAY 0.680851 (-1625 350);
PAINT MONO (-1625 350);
DISPLAY INVISIBLE (-1625 350);
FORCEADD CAP..1
(-1925 125);
FORCEPROP 1 LAST PACK_TYPE 0402
J 0
(-1875 -75);
DISPLAY 0.617021 (-1875 -75);
PAINT SKYBLUE (-1875 -75);
FORCEPROP 1 LAST PART_NUMBER D97712-011
J 0
(-1875 -25);
DISPLAY 0.617021 (-1875 -25);
PAINT BLUE (-1875 -25);
FORCEPROP 1 LASTPIN (-1925 25) $PN 2
J 0
(-1915 5);
DISPLAY 0.617021 (-1915 5);
PAINT ORANGE (-1915 5);
FORCEPROP 1 LASTPIN (-1925 225) $PN 1
J 0
(-1915 205);
DISPLAY 0.617021 (-1915 205);
PAINT ORANGE (-1915 205);
FORCEPROP 1 LAST MATERIAL X6S
J 0
(-1875 25);
DISPLAY 0.617021 (-1875 25);
PAINT SKYBLUE (-1875 25);
FORCEPROP 1 LAST VOLTAGE 16V
J 0
(-1875 125);
DISPLAY 0.617021 (-1875 125);
PAINT SKYBLUE (-1875 125);
FORCEPROP 1 LAST TOLERANCE 10%
J 0
(-1875 75);
DISPLAY 0.617021 (-1875 75);
PAINT SKYBLUE (-1875 75);
FORCEPROP 1 LAST VALUE 1.0UF
J 0
(-1875 175);
DISPLAY 0.617021 (-1875 175);
PAINT SKYBLUE (-1875 175);
FORCEPROP 1 LAST LOCATION C7A21
J 0
(-1875 225);
DISPLAY 0.617021 (-1875 225);
PAINT AQUA (-1875 225);
FORCEPROP 2 LAST CDS_LIB mstr_discrete
J 0
(-1925 125);
PAINT ORANGE (-1925 125);
DISPLAY INVISIBLE (-1925 125);
FORCEPROP 2 LAST CDS_LOCATION C7A21
J 0
(-1875 225);
DISPLAY 0.617021 (-1875 225);
PAINT AQUA (-1875 225);
DISPLAY INVISIBLE (-1875 225);
FORCEPROP 2 LAST SEC_TYPE 0402
J 0
(-1875 350);
DISPLAY 1.021277 (-1875 350);
PAINT ORANGE (-1875 350);
DISPLAY INVISIBLE (-1875 350);
FORCEPROP 2 LAST SEC 1
J 0
(-1875 350);
DISPLAY 0.680851 (-1875 350);
PAINT MONO (-1875 350);
DISPLAY INVISIBLE (-1875 350);
FORCEPROP 1 LAST PATH I79
J 0
(-1875 275);
DISPLAY 1.319149 (-1875 275);
PAINT WHITE (-1875 275);
DISPLAY INVISIBLE (-1875 275);
FORCEPROP 2 LAST ROOM VDDQ_DEF_PWR_VR
J 0
(-1875 275);
DISPLAY 1.361702 (-1875 275);
PAINT ORANGE (-1875 275);
DISPLAY INVISIBLE (-1875 275);
FORCEADD CAP..1
(-2175 125);
FORCEPROP 1 LAST PACK_TYPE 0805
J 0
(-2125 -75);
DISPLAY 0.617021 (-2125 -75);
PAINT SKYBLUE (-2125 -75);
FORCEPROP 1 LAST PART_NUMBER C95333-007
J 0
(-2125 -25);
DISPLAY 0.617021 (-2125 -25);
PAINT BLUE (-2125 -25);
FORCEPROP 1 LASTPIN (-2175 25) $PN 2
J 0
(-2165 5);
DISPLAY 0.617021 (-2165 5);
PAINT ORANGE (-2165 5);
FORCEPROP 1 LASTPIN (-2175 225) $PN 1
J 0
(-2165 205);
DISPLAY 0.617021 (-2165 205);
PAINT ORANGE (-2165 205);
FORCEPROP 1 LAST MATERIAL X6S
J 0
(-2125 25);
DISPLAY 0.617021 (-2125 25);
PAINT SKYBLUE (-2125 25);
FORCEPROP 1 LAST VOLTAGE 16V
J 0
(-2125 125);
DISPLAY 0.617021 (-2125 125);
PAINT SKYBLUE (-2125 125);
FORCEPROP 1 LAST TOLERANCE 10%
J 0
(-2125 75);
DISPLAY 0.617021 (-2125 75);
PAINT SKYBLUE (-2125 75);
FORCEPROP 1 LAST VALUE 10UF
J 0
(-2125 175);
DISPLAY 0.617021 (-2125 175);
PAINT SKYBLUE (-2125 175);
FORCEPROP 1 LAST LOCATION C3L17
J 0
(-2125 225);
DISPLAY 0.617021 (-2125 225);
PAINT AQUA (-2125 225);
FORCEPROP 2 LAST CDS_LIB mstr_discrete
J 0
(-2175 125);
PAINT ORANGE (-2175 125);
DISPLAY INVISIBLE (-2175 125);
FORCEPROP 2 LAST CDS_LOCATION C3L17
J 0
(-2125 225);
DISPLAY 0.617021 (-2125 225);
PAINT AQUA (-2125 225);
DISPLAY INVISIBLE (-2125 225);
FORCEPROP 2 LAST SEC_TYPE 0805
J 0
(-2125 350);
DISPLAY 1.021277 (-2125 350);
PAINT ORANGE (-2125 350);
DISPLAY INVISIBLE (-2125 350);
FORCEPROP 2 LAST SEC 1
J 0
(-2125 350);
DISPLAY 0.680851 (-2125 350);
PAINT MONO (-2125 350);
DISPLAY INVISIBLE (-2125 350);
FORCEPROP 1 LAST PATH I80
J 0
(-2125 275);
DISPLAY 1.319149 (-2125 275);
PAINT WHITE (-2125 275);
DISPLAY INVISIBLE (-2125 275);
FORCEPROP 2 LAST ROOM VDDQ_DEF_PWR_VR
J 0
(-2125 275);
DISPLAY 1.361702 (-2125 275);
PAINT ORANGE (-2125 275);
DISPLAY INVISIBLE (-2125 275);
FORCEADD CAP..1
(-2425 125);
FORCEPROP 1 LAST PACK_TYPE 0805
J 0
(-2375 -75);
DISPLAY 0.617021 (-2375 -75);
PAINT SKYBLUE (-2375 -75);
FORCEPROP 1 LAST PART_NUMBER C95333-007
J 0
(-2375 -25);
DISPLAY 0.617021 (-2375 -25);
PAINT BLUE (-2375 -25);
FORCEPROP 1 LASTPIN (-2425 25) $PN 2
J 0
(-2415 5);
DISPLAY 0.617021 (-2415 5);
PAINT ORANGE (-2415 5);
FORCEPROP 1 LASTPIN (-2425 225) $PN 1
J 0
(-2415 205);
DISPLAY 0.617021 (-2415 205);
PAINT ORANGE (-2415 205);
FORCEPROP 1 LAST MATERIAL X6S
J 0
(-2375 25);
DISPLAY 0.617021 (-2375 25);
PAINT SKYBLUE (-2375 25);
FORCEPROP 1 LAST VOLTAGE 16V
J 0
(-2375 125);
DISPLAY 0.617021 (-2375 125);
PAINT SKYBLUE (-2375 125);
FORCEPROP 1 LAST TOLERANCE 10%
J 0
(-2375 75);
DISPLAY 0.617021 (-2375 75);
PAINT SKYBLUE (-2375 75);
FORCEPROP 1 LAST VALUE 10UF
J 0
(-2375 175);
DISPLAY 0.617021 (-2375 175);
PAINT SKYBLUE (-2375 175);
FORCEPROP 1 LAST LOCATION C3L16
J 0
(-2375 225);
DISPLAY 0.617021 (-2375 225);
PAINT AQUA (-2375 225);
FORCEPROP 2 LAST CDS_LIB mstr_discrete
J 0
(-2425 125);
PAINT ORANGE (-2425 125);
DISPLAY INVISIBLE (-2425 125);
FORCEPROP 2 LAST CDS_LOCATION C3L16
J 0
(-2375 225);
DISPLAY 0.617021 (-2375 225);
PAINT AQUA (-2375 225);
DISPLAY INVISIBLE (-2375 225);
FORCEPROP 2 LAST SEC_TYPE 0805
J 0
(-2375 350);
DISPLAY 1.021277 (-2375 350);
PAINT ORANGE (-2375 350);
DISPLAY INVISIBLE (-2375 350);
FORCEPROP 2 LAST SEC 1
J 0
(-2375 350);
DISPLAY 0.680851 (-2375 350);
PAINT MONO (-2375 350);
DISPLAY INVISIBLE (-2375 350);
FORCEPROP 1 LAST PATH I81
J 0
(-2375 275);
DISPLAY 1.319149 (-2375 275);
PAINT WHITE (-2375 275);
DISPLAY INVISIBLE (-2375 275);
FORCEPROP 2 LAST ROOM VDDQ_DEF_PWR_VR
J 0
(-2375 275);
DISPLAY 1.361702 (-2375 275);
PAINT ORANGE (-2375 275);
DISPLAY INVISIBLE (-2375 275);
FORCEADD OFFPAGE..1
(-1800 -150);
FORCEPROP 2 LAST $XR0 218 
J 0
(-2052 -150);
DISPLAY 0.638298 (-2052 -150);
PAINT MONO (-2052 -150);
FORCEPROP 2 LAST BOM_COST PROC_VRD_VCCIN_CPU0
J 0
(-2050 -100);
DISPLAY 1.446809 (-2050 -100);
PAINT MONO (-2050 -100);
DISPLAY INVISIBLE (-2050 -100);
FORCEPROP 2 LAST CDS_LIB mstr_standard
J 0
(-1800 -150);
PAINT ORANGE (-1800 -150);
DISPLAY INVISIBLE (-1800 -150);
FORCEPROP 2 LAST PATH I82
J 0
(-1745 -75);
DISPLAY 1.361702 (-1745 -75);
PAINT ORANGE (-1745 -75);
DISPLAY INVISIBLE (-1745 -75);
FORCEPROP 1 LAST COMMENT_BODY TRUE
J 0
(-1675 -250);
DISPLAY 1.680851 (-1675 -250);
PAINT GREEN (-1675 -250);
DISPLAY INVISIBLE (-1675 -250);
FORCEPROP 1 LAST OFFPAGE TRUE
J 0
(-1475 -275);
DISPLAY 1.680851 (-1475 -275);
PAINT GREEN (-1475 -275);
DISPLAY INVISIBLE (-1475 -275);
FORCEPROP 2 LAST ROOM VDDQ_DEF_PWR_VR
J 0
(-2200 -75);
DISPLAY 1.936170 (-2200 -75);
PAINT ORANGE (-2200 -75);
DISPLAY INVISIBLE (-2200 -75);
FORCEADD VCC_CORE..1
(-2675 575);
FORCEPROP 3 LASTPIN (-2675 525) SIG_NAME VR_FET_SW_P12V_STBY_PVDDQ_DEF\g
J 0
(-2665 535);
DISPLAY 0.659574 (-2665 535);
PAINT MONO (-2665 535);
DISPLAY INVISIBLE (-2665 535);
FORCEPROP 1 LAST HDL_POWER VR_FET_SW_P12V_STBY_PVDDQ_DEF
J 1
(-2575 625);
DISPLAY 0.617021 (-2575 625);
PAINT GREEN (-2575 625);
FORCEPROP 1 LAST PATH I83
J 0
(-2625 600);
DISPLAY 1.170213 (-2625 600);
PAINT AQUA (-2625 600);
DISPLAY INVISIBLE (-2625 600);
FORCEPROP 2 LAST CDS_LIB mstr_symbols
J 0
(-2675 575);
PAINT ORANGE (-2675 575);
DISPLAY INVISIBLE (-2675 575);
FORCEADD CAP..1
(-2675 125);
FORCEPROP 1 LAST PACK_TYPE 0805
J 0
(-2625 -75);
DISPLAY 0.617021 (-2625 -75);
PAINT SKYBLUE (-2625 -75);
FORCEPROP 1 LAST PART_NUMBER C95333-007
J 0
(-2625 -25);
DISPLAY 0.617021 (-2625 -25);
PAINT BLUE (-2625 -25);
FORCEPROP 1 LASTPIN (-2675 225) $PN 1
J 0
(-2665 205);
DISPLAY 0.617021 (-2665 205);
PAINT ORANGE (-2665 205);
FORCEPROP 1 LASTPIN (-2675 25) $PN 2
J 0
(-2665 5);
DISPLAY 0.617021 (-2665 5);
PAINT ORANGE (-2665 5);
FORCEPROP 1 LAST MATERIAL X6S
J 0
(-2625 25);
DISPLAY 0.617021 (-2625 25);
PAINT SKYBLUE (-2625 25);
FORCEPROP 1 LAST VOLTAGE 16V
J 0
(-2625 125);
DISPLAY 0.617021 (-2625 125);
PAINT SKYBLUE (-2625 125);
FORCEPROP 1 LAST TOLERANCE 10%
J 0
(-2625 75);
DISPLAY 0.617021 (-2625 75);
PAINT SKYBLUE (-2625 75);
FORCEPROP 1 LAST VALUE 10UF
J 0
(-2625 175);
DISPLAY 0.617021 (-2625 175);
PAINT SKYBLUE (-2625 175);
FORCEPROP 1 LAST LOCATION C3L15
J 0
(-2625 225);
DISPLAY 0.617021 (-2625 225);
PAINT AQUA (-2625 225);
FORCEPROP 2 LAST CDS_LOCATION C3L15
J 0
(-2625 225);
DISPLAY 0.617021 (-2625 225);
PAINT AQUA (-2625 225);
DISPLAY INVISIBLE (-2625 225);
FORCEPROP 2 LAST CDS_LIB mstr_discrete
J 0
(-2675 125);
PAINT ORANGE (-2675 125);
DISPLAY INVISIBLE (-2675 125);
FORCEPROP 2 LAST ROOM VDDQ_DEF_PWR_VR
J 0
(-2625 275);
DISPLAY 1.361702 (-2625 275);
PAINT ORANGE (-2625 275);
DISPLAY INVISIBLE (-2625 275);
FORCEPROP 1 LAST PATH I84
J 0
(-2625 275);
DISPLAY 1.319149 (-2625 275);
PAINT WHITE (-2625 275);
DISPLAY INVISIBLE (-2625 275);
FORCEPROP 2 LAST SEC_TYPE 0805
J 0
(-2625 350);
DISPLAY 1.021277 (-2625 350);
PAINT ORANGE (-2625 350);
DISPLAY INVISIBLE (-2625 350);
FORCEPROP 2 LAST SEC 1
J 0
(-2625 350);
DISPLAY 0.680851 (-2625 350);
PAINT MONO (-2625 350);
DISPLAY INVISIBLE (-2625 350);
FORCEADD GND..1
(-2675 -175);
FORCEPROP 3 LASTPIN (-2675 -125) SIG_NAME GND\g
J 0
(-2665 -115);
DISPLAY 0.659574 (-2665 -115);
PAINT MONO (-2665 -115);
DISPLAY INVISIBLE (-2665 -115);
FORCEPROP 2 LAST ROOM VDDQ_DEF_PWR_VR
J 0
(-3225 -100);
DISPLAY 1.936170 (-3225 -100);
PAINT ORANGE (-3225 -100);
DISPLAY INVISIBLE (-3225 -100);
FORCEPROP 2 LAST BOM_COST PROC_VRD_VCCIN_CPU0
J 0
(-3050 -100);
DISPLAY 1.446809 (-3050 -100);
PAINT MONO (-3050 -100);
DISPLAY INVISIBLE (-3050 -100);
FORCEPROP 1 LAST BODY_TYPE PLUMBING
J 0
(-2720 -218);
DISPLAY 0.340426 (-2720 -218);
PAINT GREEN (-2720 -218);
DISPLAY INVISIBLE (-2720 -218);
FORCEPROP 1 LAST VOLTAGE 0
J 0
(-2675 -175);
PAINT SKYBLUE (-2675 -175);
DISPLAY INVISIBLE (-2675 -175);
FORCEPROP 1 LAST SIZE 1B
J 0
(-2600 -225);
DISPLAY 1.723404 (-2600 -225);
PAINT GREEN (-2600 -225);
DISPLAY INVISIBLE (-2600 -225);
FORCEPROP 2 LAST CDS_LIB mstr_symbols
J 0
(-2675 -175);
PAINT ORANGE (-2675 -175);
DISPLAY INVISIBLE (-2675 -175);
FORCEPROP 1 LAST PATH I85
J 0
(-2600 -175);
DISPLAY 1.170213 (-2600 -175);
PAINT AQUA (-2600 -175);
DISPLAY INVISIBLE (-2600 -175);
FORCEPROP 1 LAST HDL_POWER GND
J 0
(-2675 -25);
DISPLAY 1.723404 (-2675 -25);
PAINT GREEN (-2675 -25);
DISPLAY INVISIBLE (-2675 -25);
FORCEADD VCC_CORE..1
(-2500 2625);
FORCEPROP 3 LASTPIN (-2500 2575) SIG_NAME VR_FET_SW_P12V_STBY_PVDDQ_DEF\g
J 0
(-2490 2585);
DISPLAY 0.659574 (-2490 2585);
PAINT MONO (-2490 2585);
DISPLAY INVISIBLE (-2490 2585);
FORCEPROP 1 LAST HDL_POWER VR_FET_SW_P12V_STBY_PVDDQ_DEF
J 1
(-2400 2775);
DISPLAY 0.617021 (-2400 2775);
PAINT GREEN (-2400 2775);
FORCEPROP 1 LAST PATH I86
J 0
(-2450 2650);
DISPLAY 1.170213 (-2450 2650);
PAINT AQUA (-2450 2650);
DISPLAY INVISIBLE (-2450 2650);
FORCEPROP 2 LAST CDS_LIB mstr_symbols
J 0
(-2500 2625);
PAINT ORANGE (-2500 2625);
DISPLAY INVISIBLE (-2500 2625);
FORCEADD CAP..1
(4075 1575);
FORCEPROP 1 LAST MATERIAL X6S
J 0
(4125 1475);
DISPLAY 0.617021 (4125 1475);
PAINT SKYBLUE (4125 1475);
FORCEPROP 1 LAST PACK_TYPE 0805LF
J 0
(4125 1375);
DISPLAY 0.617021 (4125 1375);
PAINT SKYBLUE (4125 1375);
FORCEPROP 1 LAST PART_NUMBER C95333-002
J 0
(4125 1425);
DISPLAY 0.617021 (4125 1425);
PAINT BLUE (4125 1425);
FORCEPROP 1 LAST TOLERANCE 20%
J 0
(4125 1525);
DISPLAY 0.617021 (4125 1525);
PAINT SKYBLUE (4125 1525);
FORCEPROP 1 LAST LOCATION C6A1
J 0
(4125 1675);
DISPLAY 0.617021 (4125 1675);
PAINT AQUA (4125 1675);
FORCEPROP 1 LAST VALUE 22UF
J 0
(4125 1625);
DISPLAY 0.617021 (4125 1625);
PAINT SKYBLUE (4125 1625);
FORCEPROP 1 LASTPIN (4075 1475) $PN 2
J 0
(4085 1455);
DISPLAY 0.787234 (4085 1455);
PAINT ORANGE (4085 1455);
DISPLAY INVISIBLE (4085 1455);
FORCEPROP 1 LASTPIN (4075 1675) $PN 1
J 0
(4085 1655);
DISPLAY 0.787234 (4085 1655);
PAINT ORANGE (4085 1655);
DISPLAY INVISIBLE (4085 1655);
FORCEPROP 2 LAST CDS_LIB mstr_discrete
J 0
(4075 1575);
PAINT ORANGE (4075 1575);
DISPLAY INVISIBLE (4075 1575);
FORCEPROP 1 LAST VOLTAGE 4V
J 0
(4125 1575);
DISPLAY 1.446809 (4125 1575);
PAINT SKYBLUE (4125 1575);
DISPLAY INVISIBLE (4125 1575);
FORCEPROP 2 LAST BOM_COST PROC_VRD_VCCIN_CPU0
J 0
(4125 1725);
DISPLAY 1.446809 (4125 1725);
PAINT MONO (4125 1725);
DISPLAY INVISIBLE (4125 1725);
FORCEPROP 2 LAST CDS_SEC 1
J 0
(4130 1775);
DISPLAY 1.021277 (4130 1775);
PAINT ORANGE (4130 1775);
DISPLAY INVISIBLE (4130 1775);
FORCEPROP 2 LAST $SEC 1
J 0
(4130 1775);
DISPLAY 0.680851 (4130 1775);
PAINT MONO (4130 1775);
DISPLAY INVISIBLE (4130 1775);
FORCEPROP 2 LAST CDS_LOCATION C6A1
J 0
(4125 1675);
DISPLAY 0.617021 (4125 1675);
PAINT AQUA (4125 1675);
DISPLAY INVISIBLE (4125 1675);
FORCEPROP 1 LAST PATH I87
J 0
(4125 1725);
DISPLAY 0.978723 (4125 1725);
PAINT WHITE (4125 1725);
DISPLAY INVISIBLE (4125 1725);
FORCEPROP 2 LAST ROOM VDDQ_DEF_PWR_VR
J 0
(4125 1725);
DISPLAY 1.446809 (4125 1725);
PAINT MONO (4125 1725);
DISPLAY INVISIBLE (4125 1725);
FORCEADD P5V_STBY..1
(100 900);
FORCEPROP 3 LASTPIN (100 850) SIG_NAME P5V_STBY\g
J 0
(110 860);
DISPLAY 0.659574 (110 860);
PAINT MONO (110 860);
DISPLAY INVISIBLE (110 860);
FORCEPROP 1 LAST HDL_POWER P5V_STBY
J 0
(-200 775);
DISPLAY 0.872340 (-200 775);
PAINT ORANGE (-200 775);
DISPLAY INVISIBLE (-200 775);
FORCEPROP 1 LAST VOLTAGE 5.0V
J 0
(55 857);
DISPLAY 0.340426 (55 857);
PAINT SKYBLUE (55 857);
DISPLAY INVISIBLE (55 857);
FORCEPROP 1 LAST BODY_TYPE PLUMBING
J 0
(55 857);
DISPLAY 0.340426 (55 857);
PAINT GREEN (55 857);
DISPLAY INVISIBLE (55 857);
FORCEPROP 2 LAST CDS_LIB mstr_symbols
J 0
(100 900);
PAINT ORANGE (100 900);
DISPLAY INVISIBLE (100 900);
FORCEPROP 1 LAST PATH I89
J 0
(145 902);
DISPLAY 0.340426 (145 902);
PAINT GREEN (145 902);
DISPLAY INVISIBLE (145 902);
FORCEPROP 1 LAST SIZE 1B
J 0
(145 922);
DISPLAY 0.340426 (145 922);
PAINT GREEN (145 922);
DISPLAY INVISIBLE (145 922);
FORCEADD DNS..2
(4380 95);
PAINT RED (4380 95);
FORCEPROP 1 LAST COMMENT_BODY TRUE
R 1
J 0
(4455 -130);
DISPLAY 0.872340 (4455 -130);
PAINT GREEN (4455 -130);
DISPLAY INVISIBLE (4455 -130);
FORCEPROP 2 LAST CDS_LIB mstr_misc
J 0
(4380 95);
PAINT ORANGE (4380 95);
DISPLAY INVISIBLE (4380 95);
FORCEADD DNS..2
(4380 2245);
PAINT RED (4380 2245);
FORCEPROP 1 LAST COMMENT_BODY TRUE
R 1
J 0
(4455 2020);
DISPLAY 0.872340 (4455 2020);
PAINT GREEN (4455 2020);
DISPLAY INVISIBLE (4455 2020);
FORCEPROP 2 LAST CDS_LIB mstr_misc
J 0
(4380 2245);
PAINT ORANGE (4380 2245);
DISPLAY INVISIBLE (4380 2245);
FORCEADD INTEL_CORP_BPAGE..1
(4925 -1575);
FORCEPROP 1 LAST CDS_CON_LAST_MODIFIED Tue Dec 01 11:52:26 2015
J 0
(3500 -1250);
DISPLAY 1.936170 (3500 -1250);
PAINT GREEN (3500 -1250);
DISPLAY INVISIBLE (3500 -1250);
FORCEPROP 1 LAST CUSTOM_TXT_CDS <CURRENT_DESIGN_SHEET> OF <TOTAL_DESIGN_SHEETS>
J 0
(4425 -1550);
PAINT GREEN (4425 -1550);
FORCEPROP 1 LAST CUSTOM_TXT_CDS <CON_LAST_MODIFIED>
J 0
(3000 -1225);
PAINT GREEN (3000 -1225);
FORCEPROP 2 LAST CUSTOM_TXT_CDS <XR_PAGE_TITLE>
J 0
(-2965 3675);
DISPLAY 0.638298 (-2965 3675);
PAINT PINK (-2965 3675);
DISPLAY INVISIBLE (-2965 3675);
FORCEPROP 1 LAST SCH_ADDRESS3 Santa Clara, CA 95052-8119
J 0
(950 -1550);
DISPLAY 0.617021 (950 -1550);
PAINT GREEN (950 -1550);
FORCEPROP 1 LAST SCH_ADDRESS2 P.O. BOX 58119
J 0
(950 -1500);
DISPLAY 0.617021 (950 -1500);
PAINT GREEN (950 -1500);
FORCEPROP 1 LAST SCH_DEPT BESD
J 1
(475 -1475);
DISPLAY 1.212766 (475 -1475);
PAINT YELLOW (475 -1475);
FORCEPROP 1 LAST SCH_TITLE VDDQ DEF_VR (2 OF 3)
J 0
(-3025 -1525);
DISPLAY 1.212766 (-3025 -1525);
PAINT ORANGE (-3025 -1525);
FORCEPROP 1 LAST SCH_ADDRESS1 2200 Mission College Blvd.
J 0
(950 -1450);
DISPLAY 0.617021 (950 -1450);
PAINT GREEN (950 -1450);
FORCEPROP 1 LAST SCH_NUMBER H4694802
J 0
(3625 -1425);
DISPLAY 1.212766 (3625 -1425);
PAINT YELLOW (3625 -1425);
FORCEPROP 1 LAST SCH_REV 2.420
J 0
(4675 -1425);
DISPLAY 0.978723 (4675 -1425);
PAINT YELLOW (4675 -1425);
FORCEPROP 2 LAST ROOM CPU0_CORE_VR
J 0
(-3175 3525);
DISPLAY 1.936170 (-3175 3525);
PAINT ORANGE (-3175 3525);
DISPLAY INVISIBLE (-3175 3525);
FORCEPROP 2 LAST PAGE_BORDER TRUE
J 0
(-2965 3675);
DISPLAY 1.255319 (-2965 3675);
PAINT PINK (-2965 3675);
DISPLAY INVISIBLE (-2965 3675);
FORCEPROP 1 LAST COMMENT_BODY TRUE
J 0
(4937 -1563);
DISPLAY 0.893617 (4937 -1563);
PAINT GREEN (4937 -1563);
DISPLAY INVISIBLE (4937 -1563);
FORCEPROP 2 LAST CDS_LIB mstr_symbols
J 0
(4925 -1575);
DISPLAY 1.936170 (4925 -1575);
PAINT ORANGE (4925 -1575);
DISPLAY INVISIBLE (4925 -1575);
FORCEPROP 2 LAST CDS_XR_PAGE_TITLE CR-219 : @BASEBOARD_FAB2_LIB.BASEBOARD_FAB2(SCH_1):PAGE219
J 0
(-2965 3675);
DISPLAY 0.638298 (-2965 3675);
PAINT PINK (-2965 3675);
DISPLAY INVISIBLE (-2965 3675);
WIRE 16 -1 (1050 2225)(950 2225);
WIRE 16 -1 (950 2225)(950 1050);
WIRE 16 -1 (950 1050)(3650 1050);
WIRE 16 -1 (3650 1050)(3650 1775);
WIRE 16 -1 (3500 1775)(3650 1775);
WIRE 16 -1 (3650 1775)(4075 1775);
WIRE 16 -1 (4075 1675)(4075 1775);
WIRE 16 -1 (4075 1775)(4075 1825);
WIRE 16 -1 (4375 2000)(4375 2150);
WIRE 16 -1 (4375 -150)(4375 0);
WIRE 16 -1 (1050 2325)(950 2325);
WIRE 16 -1 (950 2325)(950 2425);
WIRE 16 -1 (1050 2425)(950 2425);
WIRE 16 -1 (950 2425)(25 2425);
WIRE 16 -1 (25 2425)(25 2950);
WIRE 16 -1 (-475 2950)(25 2950);
WIRE 16 -1 (25 2950)(25 3050);
WIRE 16 -1 (-575 2950)(-475 2950);
WIRE 16 -1 (-475 2475)(-475 2950);
WIRE 16 -1 (-575 2475)(-575 2950);
WIRE 16 -1 (-875 2950)(-575 2950);
WIRE 16 -1 (875 -650)(875 -775);
WIRE 16 -1 (825 1475)(825 1375);
WIRE 16 -1 (2600 -125)(2600 -175);
WIRE 16 -1 (2675 -975)(2675 -1050);
WIRE 16 -1 (2700 1975)(2700 1925);
WIRE 16 -1 (2800 1200)(2800 1150);
WIRE 16 -1 (2050 1675)(2400 1675);
WIRE 16 -1 (2400 1625)(2400 1675);
WIRE 16 -1 (2400 1575)(2400 1625);
WIRE 16 -1 (2400 1625)(2050 1625);
WIRE 16 -1 (2400 1575)(2050 1575);
WIRE 16 -1 (2400 1525)(2400 1575);
WIRE 16 -1 (2400 1375)(2400 1525);
WIRE 16 -1 (2400 1525)(2050 1525);
WIRE 16 -1 (-475 2275)(-475 2050);
WIRE 16 -1 (-475 2050)(-575 2050);
WIRE 16 -1 (-575 2275)(-575 2050);
WIRE 16 -1 (-1200 2050)(-575 2050);
WIRE 16 -1 (-1200 2250)(-1200 2050);
WIRE 16 -1 (-1200 2050)(-1475 2050);
WIRE 16 -1 (-1475 2275)(-1475 2050);
WIRE 16 -1 (-1725 2050)(-1475 2050);
WIRE 16 -1 (-1725 2275)(-1725 2050);
WIRE 16 -1 (-2000 2050)(-1725 2050);
WIRE 16 -1 (-2000 2275)(-2000 2050);
WIRE 16 -1 (-2250 2050)(-2000 2050);
WIRE 16 -1 (-2250 2275)(-2250 2050);
WIRE 16 -1 (-2500 2050)(-2250 2050);
WIRE 16 -1 (-2500 2300)(-2500 2050);
WIRE 16 -1 (-2500 2000)(-2500 2050);
WIRE 16 -1 (1075 100)(975 100);
WIRE 16 -1 (975 100)(975 -1150);
WIRE 16 -1 (975 -1150)(3500 -1150);
WIRE 16 -1 (3500 -1150)(3500 -350);
WIRE 16 -1 (3275 -350)(3500 -350);
WIRE 16 -1 (3500 -350)(4100 -350);
WIRE 16 -1 (4100 -450)(4100 -350);
WIRE 16 -1 (4100 -350)(4100 -300);
WIRE 16 -1 (4100 -725)(4100 -650);
WIRE 16 -1 (4075 1400)(4075 1475);
WIRE 16 -1 (2075 -450)(2425 -450);
WIRE 16 -1 (2425 -500)(2425 -450);
WIRE 16 -1 (2425 -500)(2075 -500);
WIRE 16 -1 (2425 -550)(2425 -500);
WIRE 16 -1 (2425 -600)(2425 -550);
WIRE 16 -1 (2425 -550)(2075 -550);
WIRE 16 -1 (2425 -750)(2425 -600);
WIRE 16 -1 (2425 -600)(2075 -600);
WIRE 16 -1 (1075 450)(725 450);
WIRE 16 -1 (725 450)(725 400);
WIRE 16 -1 (1075 400)(725 400);
WIRE 16 -1 (725 400)(-1675 400);
WIRE 16 -1 (-1675 225)(-1675 400);
WIRE 16 -1 (-1675 400)(-1925 400);
WIRE 16 -1 (-1925 225)(-1925 400);
WIRE 16 -1 (-1925 400)(-2175 400);
WIRE 16 -1 (-2175 225)(-2175 400);
WIRE 16 -1 (-2175 400)(-2425 400);
WIRE 16 -1 (-2425 225)(-2425 400);
WIRE 16 -1 (-2425 400)(-2675 400);
WIRE 16 -1 (-2675 225)(-2675 400);
WIRE 16 -1 (-2675 525)(-2675 400);
WIRE 16 -1 (-550 150)(-550 -75);
WIRE 16 -1 (-550 -75)(-725 -75);
WIRE 16 -1 (-725 150)(-725 -75);
WIRE 16 -1 (-725 -75)(-1400 -75);
WIRE 16 -1 (-1400 50)(-1400 -75);
WIRE 16 -1 (-1400 -75)(-1675 -75);
WIRE 16 -1 (-1675 25)(-1675 -75);
WIRE 16 -1 (-1675 -75)(-1925 -75);
WIRE 16 -1 (-1925 25)(-1925 -75);
WIRE 16 -1 (-1925 -75)(-2175 -75);
WIRE 16 -1 (-2175 25)(-2175 -75);
WIRE 16 -1 (-2175 -75)(-2425 -75);
WIRE 16 -1 (-2425 25)(-2425 -75);
WIRE 16 -1 (-2425 -75)(-2675 -75);
WIRE 16 -1 (-2675 25)(-2675 -75);
WIRE 16 -1 (-2675 -125)(-2675 -75);
WIRE 16 -1 (1050 2575)(900 2575);
WIRE 16 -1 (900 2575)(900 2525);
WIRE 16 -1 (1050 2525)(900 2525);
WIRE 16 -1 (900 2525)(-1475 2525);
WIRE 16 -1 (-1475 2475)(-1475 2525);
WIRE 16 -1 (-1725 2525)(-1475 2525);
WIRE 16 -1 (-1725 2475)(-1725 2525);
WIRE 16 -1 (-2000 2525)(-1725 2525);
WIRE 16 -1 (-2000 2475)(-2000 2525);
WIRE 16 -1 (-2250 2525)(-2000 2525);
WIRE 16 -1 (-2250 2475)(-2250 2525);
WIRE 16 -1 (-2500 2525)(-2250 2525);
WIRE 16 -1 (-2500 2500)(-2500 2525);
WIRE 16 -1 (-2500 2575)(-2500 2525);
WIRE 16 -1 (1075 200)(950 200);
WIRE 16 -1 (950 200)(950 300);
WIRE 16 -1 (1075 300)(950 300);
WIRE 16 -1 (950 300)(100 300);
WIRE 16 -1 (100 775)(100 300);
WIRE 16 -1 (100 775)(-550 775);
WIRE 16 -1 (100 775)(100 850);
WIRE 16 -1 (-550 775)(-725 775);
WIRE 16 -1 (-550 350)(-550 775);
WIRE 16 -1 (-725 350)(-725 775);
WIRE 16 -1 (-725 775)(-1000 775);
WIRE 16 -1 (1075 500)(-1400 500);
WIRE 16 -1 (-1400 500)(-1400 775);
FORCEPROP 2 LAST SIG_NAME VR_PVDDQ_DEF_PH2_VCIN
J 0
(-1365 510);
DISPLAY 0.617021 (-1365 510);
PAINT ORANGE (-1365 510);
FORCEPROP 2 LASTPROP $XRERR UNIQUE?
J 0
(-1605 510);
DISPLAY 0.638298 (-1605 510);
PAINT MONO (-1605 510);
DISPLAY INVISIBLE (-1605 510);
WIRE 16 -1 (-1400 250)(-1400 500);
WIRE 16 -1 (-1400 775)(-1200 775);
WIRE 16 -1 (2075 500)(3300 500);
FORCEPROP 2 LAST SIG_NAME ISENSE_PVDDQ_DEF_PH2_IMON
J 0
(2462 510);
DISPLAY 0.617021 (2462 510);
PAINT ORANGE (2462 510);
WIRE 16 -1 (-1000 -600)(675 -600);
FORCEPROP 2 LAST SIG_NAME VR_PVDDQ_DEF_PH2_PHASE
J 0
(-990 -590);
DISPLAY 0.617021 (-990 -590);
PAINT ORANGE (-990 -590);
FORCEPROP 2 LASTPROP $XRERR UNIQUE?
J 0
(-1230 -590);
DISPLAY 0.638298 (-1230 -590);
PAINT MONO (-1230 -590);
DISPLAY INVISIBLE (-1230 -590);
WIRE 16 -1 (-1000 -600)(-1000 -550);
WIRE 16 -1 (675 -600)(675 -400);
WIRE 16 -1 (675 -400)(1075 -400);
WIRE 16 2175 (-1075 375)(-325 375);
WIRE 16 2175 (-1075 375)(-1075 -50);
WIRE 16 2175 (-325 375)(-325 -50);
WIRE 16 2175 (-1075 -50)(-325 -50);
WIRE 16 -1 (1050 2625)(-1200 2625);
FORCEPROP 2 LAST SIG_NAME VR_PVDDQ_DEF_PH1_VCIN
J 0
(-1165 2635);
DISPLAY 0.617021 (-1165 2635);
PAINT ORANGE (-1165 2635);
FORCEPROP 2 LASTPROP $XRERR UNIQUE?
J 0
(-1405 2635);
DISPLAY 0.638298 (-1405 2635);
PAINT MONO (-1405 2635);
DISPLAY INVISIBLE (-1405 2635);
WIRE 16 -1 (-1200 2625)(-1200 2950);
WIRE 16 -1 (-1200 2450)(-1200 2625);
WIRE 16 -1 (-1200 2950)(-1075 2950);
WIRE 16 -1 (75 2075)(1050 2075);
FORCEPROP 0 LAST SIG_NAME TP_PVDDQ_DEF_PH1_GL_0
J 0
(102 2090);
DISPLAY 0.617021 (102 2090);
PAINT ORANGE (102 2090);
FORCEPROP 2 LASTPROP $XRERR UNIQUE?
J 0
(-165 2075);
DISPLAY 0.638298 (-165 2075);
PAINT MONO (-165 2075);
DISPLAY INVISIBLE (-165 2075);
WIRE 16 -1 (75 2125)(1050 2125);
FORCEPROP 0 LAST SIG_NAME TP_PVDDQ_DEF_PH1_GL_1
J 0
(102 2140);
DISPLAY 0.617021 (102 2140);
PAINT ORANGE (102 2140);
FORCEPROP 2 LASTPROP $XRERR UNIQUE?
J 0
(-165 2125);
DISPLAY 0.638298 (-165 2125);
PAINT MONO (-165 2125);
DISPLAY INVISIBLE (-165 2125);
WIRE 16 -1 (100 0)(1075 0);
FORCEPROP 0 LAST SIG_NAME TP_PVDDQ_DEF_PH2_GL_1
J 0
(127 15);
DISPLAY 0.617021 (127 15);
PAINT ORANGE (127 15);
FORCEPROP 2 LASTPROP $XRERR UNIQUE?
J 0
(-140 0);
DISPLAY 0.638298 (-140 0);
PAINT MONO (-140 0);
DISPLAY INVISIBLE (-140 0);
WIRE 16 -1 (100 -50)(1075 -50);
FORCEPROP 0 LAST SIG_NAME TP_PVDDQ_DEF_PH2_GL_0
J 0
(127 -35);
DISPLAY 0.617021 (127 -35);
PAINT ORANGE (127 -35);
FORCEPROP 2 LASTPROP $XRERR UNIQUE?
J 0
(-140 -50);
DISPLAY 0.638298 (-140 -50);
PAINT MONO (-140 -50);
DISPLAY INVISIBLE (-140 -50);
WIRE 16 -1 (2075 250)(2700 250);
FORCEPROP 2 LAST SIG_NAME NC_PVDDQ_DEF_PH2_P31
J 0
(2187 260);
DISPLAY 0.617021 (2187 260);
PAINT ORANGE (2187 260);
FORCEPROP 2 LASTPROP $XRERR UNIQUE?
J 0
(2730 250);
DISPLAY 0.638298 (2730 250);
PAINT MONO (2730 250);
DISPLAY INVISIBLE (2730 250);
WIRE 16 -1 (-1750 -150)(1075 -150);
FORCEPROP 2 LAST SIG_NAME VR_PVDDQ_DEF_PWM2
J 0
(-1763 -140);
DISPLAY 0.617021 (-1763 -140);
PAINT ORANGE (-1763 -140);
WIRE 16 -1 (2050 2375)(2750 2375);
FORCEPROP 2 LAST SIG_NAME NC_PVDDQ_DEF_PH1_P31
J 0
(2187 2385);
DISPLAY 0.617021 (2187 2385);
PAINT ORANGE (2187 2385);
FORCEPROP 2 LASTPROP $XRERR UNIQUE?
J 0
(2780 2375);
DISPLAY 0.638298 (2780 2375);
PAINT MONO (2780 2375);
DISPLAY INVISIBLE (2780 2375);
WIRE 16 -1 (2800 1550)(2800 1450);
WIRE 16 2175 (-900 2500)(-200 2500);
WIRE 16 2175 (-900 2500)(-900 2075);
WIRE 16 2175 (-200 2500)(-200 2075);
WIRE 16 2175 (-900 2075)(-200 2075);
WIRE 16 -1 (-1650 1975)(1050 1975);
WIRE 16 -1 (2075 300)(4375 300);
FORCEPROP 0 LAST VOLTAGE 3.6
J 0
(2150 375);
DISPLAY 1.021277 (2150 375);
PAINT SKYBLUE (2150 375);
DISPLAY INVISIBLE (2150 375);
FORCEPROP 2 LAST SIG_NAME VR_PVDDQ_DEF_PH2_OCSET
J 0
(2207 316);
DISPLAY 0.617021 (2207 316);
PAINT ORANGE (2207 316);
FORCEPROP 2 LASTPROP $XRERR UNIQUE?
J 0
(1967 316);
DISPLAY 0.638298 (1967 316);
PAINT MONO (1967 316);
DISPLAY INVISIBLE (1967 316);
WIRE 16 -1 (4375 200)(4375 300);
WIRE 16 2175 (-1675 1900)(-725 1900);
WIRE 16 2175 (-1675 1900)(-1675 1500);
WIRE 16 2175 (-725 1900)(-725 1500);
WIRE 16 2175 (-1675 1500)(-725 1500);
WIRE 16 -1 (-1300 1850)(-450 1850);
FORCEPROP 2 LAST SIG_NAME VR_PVDDQ_DEF_PH1_BOOT
J 0
(-1290 1860);
DISPLAY 0.617021 (-1290 1860);
PAINT ORANGE (-1290 1860);
FORCEPROP 2 LASTPROP $XRERR UNIQUE?
J 0
(-1530 1860);
DISPLAY 0.638298 (-1530 1860);
PAINT MONO (-1530 1860);
DISPLAY INVISIBLE (-1530 1860);
WIRE 16 -1 (-1300 1850)(-1300 1825);
WIRE 3 2175 (-550 1950)(-150 1950);
WIRE 3 2175 (-550 1950)(-550 1675);
WIRE 3 2175 (-150 1950)(-150 1675);
WIRE 3 2175 (-550 1675)(-150 1675);
WIRE 16 -1 (-1300 1575)(550 1575);
FORCEPROP 2 LAST SIG_NAME VR_PVDDQ_DEF_PH1_PHASE
J 0
(-1265 1585);
DISPLAY 0.617021 (-1265 1585);
PAINT ORANGE (-1265 1585);
FORCEPROP 2 LASTPROP $XRERR UNIQUE?
J 0
(-1505 1585);
DISPLAY 0.638298 (-1505 1585);
PAINT MONO (-1505 1585);
DISPLAY INVISIBLE (-1505 1585);
WIRE 16 -1 (-1300 1575)(-1300 1625);
WIRE 16 -1 (550 1575)(550 1725);
WIRE 16 -1 (550 1725)(1050 1725);
WIRE 16 -1 (3575 2950)(825 2950);
FORCEPROP 2 LAST SIG_NAME VR_PVDDQ_DEF_AIREF1
J 0
(2860 2964);
DISPLAY 0.617021 (2860 2964);
PAINT ORANGE (2860 2964);
WIRE 16 -1 (825 1875)(825 2950);
WIRE 16 -1 (1050 1875)(825 1875);
WIRE 16 -1 (825 1675)(825 1875);
WIRE 16 -1 (-250 1850)(550 1850);
FORCEPROP 2 LAST SIG_NAME VR_PVDDQ_DEF_PH1_BOOT_R
J 0
(-90 1860);
DISPLAY 0.617021 (-90 1860);
PAINT ORANGE (-90 1860);
FORCEPROP 2 LASTPROP $XRERR UNIQUE?
J 0
(-330 1860);
DISPLAY 0.638298 (-330 1860);
PAINT MONO (-330 1860);
DISPLAY INVISIBLE (-330 1860);
WIRE 16 -1 (550 1850)(550 1775);
WIRE 16 -1 (550 1775)(1050 1775);
WIRE 3 2175 (475 1275)(1125 1275);
WIRE 3 2175 (475 1825)(475 1275);
WIRE 3 2175 (1125 1825)(1125 1275);
WIRE 3 2175 (475 1825)(1125 1825);
WIRE 3 2175 (2425 2225)(2925 2225);
WIRE 3 2175 (2425 2225)(2425 1850);
WIRE 3 2175 (2925 2225)(2925 1850);
WIRE 3 2175 (2425 1850)(2925 1850);
WIRE 3 2175 (-275 -375)(100 -375);
WIRE 3 2175 (-275 -200)(-275 -375);
WIRE 3 2175 (100 -200)(100 -375);
WIRE 3 2175 (-275 -200)(100 -200);
WIRE 16 -1 (-200 -275)(-1000 -275);
FORCEPROP 2 LAST SIG_NAME VR_PVDDQ_DEF_PH2_BOOT
J 0
(-990 -265);
DISPLAY 0.617021 (-990 -265);
PAINT ORANGE (-990 -265);
FORCEPROP 2 LASTPROP $XRERR UNIQUE?
J 0
(-1230 -265);
DISPLAY 0.638298 (-1230 -265);
PAINT MONO (-1230 -265);
DISPLAY INVISIBLE (-1230 -265);
WIRE 16 -1 (-1000 -275)(-1000 -350);
WIRE 16 -1 (675 -350)(1075 -350);
WIRE 16 -1 (675 -350)(675 -275);
WIRE 16 -1 (675 -275)(0 -275);
FORCEPROP 2 LAST SIG_NAME VR_PVDDQ_DEF_PH2_BOOT_R
J 0
(160 -265);
DISPLAY 0.617021 (160 -265);
PAINT ORANGE (160 -265);
FORCEPROP 2 LASTPROP $XRERR UNIQUE?
J 0
(-80 -265);
DISPLAY 0.638298 (-80 -265);
PAINT MONO (-80 -265);
DISPLAY INVISIBLE (-80 -265);
WIRE 3 2175 (600 -900)(1150 -900);
WIRE 3 2175 (600 -300)(600 -900);
WIRE 3 2175 (1150 -300)(1150 -900);
WIRE 3 2175 (600 -300)(1150 -300);
WIRE 16 -1 (2075 150)(2600 150);
FORCEPROP 2 LAST SIG_NAME A_TSENSE_PVDDQ_DEF
J 0
(2087 160);
DISPLAY 0.617021 (2087 160);
PAINT ORANGE (2087 160);
WIRE 16 -1 (2075 150)(2075 0);
WIRE 16 -1 (2600 150)(3475 150);
WIRE 16 -1 (2600 75)(2600 150);
WIRE 3 2175 (2500 200)(2975 200);
WIRE 3 2175 (2500 200)(2500 -275);
WIRE 3 2175 (2975 200)(2975 -275);
WIRE 3 2175 (2500 -275)(2975 -275);
WIRE 16 -1 (2675 -600)(2675 -725);
WIRE 16 -1 (875 825)(3225 825);
FORCEPROP 2 LAST SIG_NAME VR_PVDDQ_DEF_AIREF2
J 0
(2798 831);
DISPLAY 0.617021 (2798 831);
PAINT ORANGE (2798 831);
WIRE 16 -1 (875 -250)(875 825);
WIRE 16 -1 (1075 -250)(875 -250);
WIRE 16 -1 (875 -450)(875 -250);
WIRE 16 -1 (2050 1775)(2800 1775);
FORCEPROP 2 LAST SIG_NAME VR_PVDDQ_DEF_PH1_SW
J 0
(2135 1785);
DISPLAY 0.617021 (2135 1785);
PAINT ORANGE (2135 1785);
FORCEPROP 2 LASTPROP $XRERR UNIQUE?
J 0
(1895 1785);
DISPLAY 0.638298 (1895 1785);
PAINT MONO (1895 1785);
DISPLAY INVISIBLE (1895 1785);
WIRE 16 -1 (2800 1775)(3300 1775);
WIRE 16 -1 (2800 1700)(2800 1775);
WIRE 16 -1 (2050 2425)(4375 2425);
FORCEPROP 0 LAST VOLTAGE 3.6
J 0
(2125 2500);
DISPLAY 1.021277 (2125 2500);
PAINT SKYBLUE (2125 2500);
DISPLAY INVISIBLE (2125 2500);
FORCEPROP 2 LAST SIG_NAME VR_PVDDQ_DEF_PH1_OCSET
J 0
(2182 2441);
DISPLAY 0.617021 (2182 2441);
PAINT ORANGE (2182 2441);
FORCEPROP 2 LASTPROP $XRERR UNIQUE?
J 0
(1942 2441);
DISPLAY 0.638298 (1942 2441);
PAINT MONO (1942 2441);
DISPLAY INVISIBLE (1942 2441);
WIRE 16 -1 (4375 2350)(4375 2425);
WIRE 16 -1 (2050 2250)(2700 2250);
FORCEPROP 2 LAST SIG_NAME A_TSENSE_PVDDQ_DEF
J 0
(2087 2260);
DISPLAY 0.617021 (2087 2260);
PAINT ORANGE (2087 2260);
WIRE 16 -1 (2050 2250)(2050 2125);
WIRE 16 -1 (2700 2250)(3175 2250);
WIRE 16 -1 (2700 2175)(2700 2250);
WIRE 16 -1 (2050 2625)(3550 2625);
FORCEPROP 2 LAST SIG_NAME ISENSE_PVDDQ_DEF_PH1_IMON
J 0
(2437 2635);
DISPLAY 0.617021 (2437 2635);
PAINT ORANGE (2437 2635);
WIRE 3 2175 (2575 1075)(3125 1075);
WIRE 3 2175 (2575 1825)(2575 1075);
WIRE 3 2175 (3125 1825)(3125 1075);
WIRE 3 2175 (2575 1825)(3125 1825);
WIRE 3 2175 (2500 -375)(3000 -375);
WIRE 3 2175 (2500 -375)(2500 -1125);
WIRE 3 2175 (3000 -375)(3000 -1125);
WIRE 3 2175 (2500 -1125)(3000 -1125);
WIRE 16 -1 (2075 -350)(2675 -350);
FORCEPROP 2 LAST SIG_NAME VR_PVDDQ_DEF_PH2_SW
J 0
(2235 -340);
DISPLAY 0.617021 (2235 -340);
PAINT ORANGE (2235 -340);
FORCEPROP 2 LASTPROP $XRERR UNIQUE?
J 0
(1995 -340);
DISPLAY 0.638298 (1995 -340);
PAINT MONO (1995 -340);
DISPLAY INVISIBLE (1995 -340);
WIRE 16 -1 (2675 -350)(3075 -350);
WIRE 16 -1 (2675 -450)(2675 -350);
WIRE 16 2175 (-1325 -700)(-500 -700);
WIRE 16 2175 (-1325 -225)(-1325 -700);
WIRE 16 2175 (-500 -225)(-500 -700);
WIRE 16 2175 (-1325 -225)(-500 -225);
DOT 1 (2675 -350);
DOT 1 (-725 775);
DOT 1 (-550 775);
DOT 1 (4075 1775);
DOT 1 (2400 1625);
DOT 1 (950 2425);
DOT 1 (900 2525);
DOT 1 (25 2950);
DOT 1 (950 300);
DOT 1 (725 400);
DOT 1 (4100 -350);
DOT 1 (3500 -350);
DOT 1 (2425 -600);
DOT 1 (2425 -550);
DOT 1 (-475 2950);
DOT 1 (-575 2950);
DOT 1 (-1200 2625);
DOT 1 (-1475 2525);
DOT 1 (-2000 2525);
DOT 1 (-1200 2050);
DOT 1 (-1725 2050);
DOT 1 (-1475 2050);
DOT 1 (-2000 2050);
DOT 1 (-1400 500);
DOT 1 (-1675 400);
DOT 1 (-1925 400);
DOT 1 (-2250 2525);
DOT 1 (-2500 2525);
DOT 1 (-2250 2050);
DOT 1 (-2500 2050);
DOT 1 (-2175 400);
DOT 1 (-2425 400);
DOT 1 (-2675 400);
DOT 1 (-725 -75);
DOT 1 (-1400 -75);
DOT 1 (-1675 -75);
DOT 1 (-1925 -75);
DOT 1 (-2175 -75);
DOT 1 (-2425 -75);
DOT 1 (-2675 -75);
DOT 1 (3650 1775);
DOT 1 (2400 1525);
DOT 1 (2400 1575);
DOT 1 (-575 2050);
DOT 1 (-1725 2525);
DOT 1 (875 -250);
DOT 1 (100 775);
DOT 1 (2600 150);
DOT 1 (2700 2250);
DOT 1 (2425 -500);
DOT 1 (825 1875);
DOT 1 (2800 1775);
FORCENOTE
TP FAB1 3.01 OHM NEED CHANGE TO 2.2 OHM BUT WAIT FOR SYMBOL
(3025 -1075) 0;
DISPLAY LEFT (3025 -1075);
DISPLAY 0.851064 (3025 -1075);
PAINT RED (3025 -1075);
FORCENOTE
TP FAB1 CO-LAY WITH TI PARTS 11/16
(3025 -1000) 0;
DISPLAY LEFT (3025 -1000);
DISPLAY 0.851064 (3025 -1000);
PAINT RED (3025 -1000);
FORCENOTE
TP FAB1 CO-LAY WITH TI PARTS 11/16
(3000 -150) 0;
DISPLAY LEFT (3000 -150);
DISPLAY 0.851064 (3000 -150);
PAINT RED (3000 -150);
FORCENOTE
TP FAB1 CO-LAY WITH TI PARTS 11/16
(2950 1000) 0;
DISPLAY LEFT (2950 1000);
DISPLAY 0.851064 (2950 1000);
PAINT RED (2950 1000);
FORCENOTE
TP FAB1 3.01 OHM NEED CHANGE TO 2.2 OHM BUT WAIT FOR SYMBOL
(2950 950) 0;
DISPLAY LEFT (2950 950);
DISPLAY 0.851064 (2950 950);
PAINT RED (2950 950);
FORCENOTE
TP FAB1 CO-LAY WITH TI PARTS 11/16
(3125 2050) 0;
DISPLAY LEFT (3125 2050);
DISPLAY 0.851064 (3125 2050);
PAINT RED (3125 2050);
FORCENOTE
ROOM = VDDQ_DEF_PWR_VR
(-3005 -1400) 0;
DISPLAY LEFT (-3005 -1400);
DISPLAY 2.893617 (-3005 -1400);
PAINT PURPLE (-3005 -1400);
FORCENOTE
TP FAB1 CO-LAY WITH TI PARTS 11/16
(-625 1425) 0;
DISPLAY LEFT (-625 1425);
DISPLAY 0.851064 (-625 1425);
PAINT RED (-625 1425);
FORCENOTE
SPOF
(-1380 1400) 0;
DISPLAY LEFT (-1380 1400);
DISPLAY 1.936170 (-1380 1400);
PAINT PURPLE (-1380 1400);
FORCENOTE
PLACE ON TOP
(-1030 -50) 0;
DISPLAY LEFT (-1030 -50);
DISPLAY 1.553191 (-1030 -50);
PAINT PURPLE (-1030 -50);
FORCENOTE
PLACE ON TOP
(-880 2100) 0;
DISPLAY LEFT (-880 2100);
DISPLAY 1.553191 (-880 2100);
PAINT PURPLE (-880 2100);
FORCENOTE
SPOF
(-1105 -775) 0;
DISPLAY LEFT (-1105 -775);
DISPLAY 1.808511 (-1105 -775);
PAINT PURPLE (-1105 -775);
FORCENOTE
TP FAB1 CO-LAY WITH TI PARTS 11/16
(-325 -700) 0;
DISPLAY LEFT (-325 -700);
DISPLAY 0.851064 (-325 -700);
PAINT RED (-325 -700);
QUIT
